G04 ================== begin FILE IDENTIFICATION RECORD ==================*
G04 Layout Name:  9048_F0T_Management_Board_D_brd_V04_1213_1625.brd*
G04 Film Name:    top*
G04 File Format:  Gerber RS274X*
G04 File Origin:  Cadence Allegro 17.2-S081*
G04 Origin Date:  Tue Dec 13 16:31:09 2022*
G04 *
G04 Layer:  DRAWING FORMAT/TITLE_BLOCK_A*
G04 Layer:  DRAWING FORMAT/TITLE_BLOCK*
G04 Layer:  VIA CLASS/TOP*
G04 Layer:  PIN/TOP*
G04 Layer:  MANUFACTURING/PHOTOPLOT_OUTLINE*
G04 Layer:  ETCH/TOP*
G04 Layer:  DRAWING FORMAT/TITLE_DATA_TOP*
G04 *
G04 Offset:    (0.00 0.00)*
G04 Mirror:    No*
G04 Mode:      Positive*
G04 Rotation:  0*
G04 FullContactRelief:  No*
G04 UndefLineWidth:     6.00*
G04 ================== end FILE IDENTIFICATION RECORD ====================*
%FSLAX25Y25*MOIN*%
%IR0*IPPOS*OFA0.00000B0.00000*MIA0B0*SFA1.00000B1.00000*%
%AMMACRO30*
4,1,32,-.01575,.06201,
-.01575,.0502,
.00197,.0502,
.00197,.04035,
-.01575,.04035,
-.01575,.03248,
.00197,.03248,
.00197,.02461,
-.01575,.02461,
-.01575,.01673,
.00197,.01673,
.00197,.00886,
-.01575,.00886,
-.01575,.00098,
.00197,.00098,
.00197,-.00689,
-.01575,-.00689,
-.01575,-.01476,
.00197,-.01476,
.00197,-.02264,
-.01575,-.02264,
-.01575,-.03051,
.00197,-.03051,
.00197,-.03839,
-.01575,-.03839,
-.01575,-.04626,
.00197,-.04626,
.00197,-.05413,
-.01575,-.05413,
-.01575,-.06201,
.01575,-.06201,
.01575,.06201,
-.01575,.06201,
0.0*
%
%ADD30MACRO30*%
%ADD51R,.109X.04*%
%ADD62R,.049X.11*%
%ADD12C,.02*%
%ADD113R,.231X.056*%
%ADD34R,.032X.007*%
%ADD11C,.03*%
%ADD121C,.041*%
%ADD120R,.105X.069*%
%ADD63C,.016*%
%ADD47C,.061*%
%ADD97R,.069X.105*%
%ADD95C,.044*%
%ADD45C,.026*%
%ADD64C,.018*%
%ADD14C,.036*%
%ADD117C,.0145*%
%ADD43R,.13X.0848*%
%ADD105R,.032X.032*%
%ADD61C,.048*%
%ADD17C,.039*%
%ADD98C,.067*%
%ADD10C,.085*%
%AMMACRO123*
4,1,8,.078,-.0425,
.078,.0425,
-.078,.0425,
-.078,-.0425,
-.0236,-.0425,
-.0236,-.0145,
.0236,-.0145,
.0236,-.0425,
.078,-.0425,
0.0*
%
%ADD123MACRO123*%
%ADD48R,.061X.061*%
%ADD99R,.044X.044*%
%ADD125C,.0395*%
%ADD58R,.048X.048*%
%ADD126C,.0785*%
%AMMACRO20*
4,1,28,-.00748,-.00052,
-.00984,-.00052,
-.00984,-.00603,
-.009782,-.006705,
-.009607,-.007359,
-.009321,-.007974,
-.008933,-.008529,
-.008455,-.009009,
-.0079,-.009398,
-.007286,-.009685,
-.006632,-.009861,
-.005957,-.00992,
-.00591,-.00992,
.00591,-.00992,
.006585,-.009869,
.007242,-.009701,
.007859,-.009421,
.008418,-.009039,
.008903,-.008565,
.009297,-.008015,
.009591,-.007404,
.009773,-.006751,
.00984,-.006077,
.00984,-.00603,
.00984,-.00052,
.00748,-.00052,
.00748,.00991,
-.00748,.00991,
-.00748,-.00052,
0.0*
%
%ADD20MACRO20*%
%AMMACRO56*
4,1,5,.00098,-.01378,
-.00492,-.01378,
-.00492,.01378,
.00492,.01378,
.00492,-.00984,
.00098,-.01378,
0.0*
%
%ADD56MACRO56*%
%AMMACRO39*
4,1,5,.01378,.00098,
.01378,-.00492,
-.01378,-.00492,
-.01378,.00492,
.00984,.00492,
.01378,.00098,
0.0*
%
%ADD39MACRO39*%
%AMMACRO21*
4,1,28,-.00052,.00748,
-.00052,.00984,
-.00603,.00984,
-.006705,.009782,
-.007359,.009607,
-.007974,.009321,
-.008529,.008933,
-.009009,.008455,
-.009398,.0079,
-.009685,.007286,
-.009861,.006632,
-.00992,.005957,
-.00992,.00591,
-.00992,-.00591,
-.009869,-.006585,
-.009701,-.007242,
-.009421,-.007859,
-.009039,-.008418,
-.008565,-.008903,
-.008015,-.009297,
-.007404,-.009591,
-.006751,-.009773,
-.006077,-.00984,
-.00603,-.00984,
-.00052,-.00984,
-.00052,-.00748,
.00991,-.00748,
.00991,.00748,
-.00052,.00748,
0.0*
%
%ADD21MACRO21*%
%ADD13R,.079X.079*%
%AMMACRO19*
4,1,28,-.00748,.00051,
-.00984,.00051,
-.00984,.00602,
-.009782,.006695,
-.009607,.007349,
-.009321,.007964,
-.008933,.008519,
-.008455,.008998,
-.0079,.009388,
-.007287,.009675,
-.006632,.009851,
-.005958,.00991,
-.00591,.00991,
.00591,.00991,
.006585,.009859,
.007242,.009691,
.007859,.009411,
.008418,.009029,
.008903,.008555,
.009297,.008005,
.00959,.007394,
.009773,.006742,
.00984,.006068,
.00984,.00602,
.00984,.00051,
.00748,.00051,
.00748,-.00992,
-.00748,-.00992,
-.00748,.00051,
0.0*
%
%ADD19MACRO19*%
%AMMACRO44*
4,1,5,-.00098,-.01378,
.00492,-.01378,
.00492,.01378,
-.00492,.01378,
-.00492,-.00984,
-.00098,-.01378,
0.0*
%
%ADD44MACRO44*%
%AMMACRO38*
4,1,5,.01378,-.00098,
.01378,.00492,
-.01378,.00492,
-.01378,-.00492,
.00984,-.00492,
.01378,-.00098,
0.0*
%
%ADD38MACRO38*%
%AMMACRO29*
4,1,28,.00051,.00748,
.00051,.00984,
.00602,.00984,
.006695,.009782,
.007349,.009607,
.007964,.009321,
.008519,.008933,
.008998,.008455,
.009388,.0079,
.009675,.007287,
.009851,.006632,
.00991,.005958,
.00991,.00591,
.00991,-.00591,
.009859,-.006585,
.009691,-.007242,
.009411,-.007859,
.009029,-.008418,
.008555,-.008903,
.008005,-.009297,
.007394,-.00959,
.006742,-.009773,
.006068,-.00984,
.00602,-.00984,
.00051,-.00984,
.00051,-.00748,
-.00992,-.00748,
-.00992,.00748,
.00051,.00748,
0.0*
%
%ADD29MACRO29*%
%ADD28R,.13X.13*%
%AMMACRO33*
4,1,5,.01772,.00591,
-.01772,.00591,
-.01772,0.0,
-.01181,-.00591,
.01772,-.00591,
.01772,.00591,
0.0*
%
%ADD33MACRO33*%
%ADD124R,.012X.02*%
%ADD86R,.025X.01*%
%ADD31R,.032X.012*%
%ADD108R,.034X.02*%
%ADD102R,.01X.025*%
%ADD65R,.02X.016*%
%ADD41R,.01X.052*%
%ADD116R,.024X.022*%
%ADD84R,.022X.032*%
%ADD82R,.02X.017*%
%ADD49R,.015X.04*%
%ADD35R,.04X.05*%
%ADD115R,.04X.015*%
%ADD92R,.036X.011*%
%ADD70R,.028X.01*%
%ADD50R,.017X.02*%
%ADD40R,.01X.036*%
%ADD119R,.011X.036*%
%ADD75R,.011X.063*%
%ADD68R,.01X.028*%
%ADD57R,.018X.02*%
%ADD91R,.024X.042*%
%ADD89R,.061X.024*%
%ADD73R,.011X.028*%
%ADD110R,.046X.013*%
%ADD109R,.034X.016*%
%ADD88C,.131*%
%ADD85R,.023X.018*%
%ADD80R,.036X.014*%
%ADD79R,.04X.028*%
%ADD60R,.014X.044*%
%ADD46R,.024X.017*%
%ADD103R,.014X.036*%
%ADD100R,.018X.023*%
%ADD87R,.017X.024*%
%ADD76R,.056X.04*%
%ADD59R,.013X.046*%
%ADD52R,.028X.04*%
%ADD36R,.032X.028*%
%ADD104R,.052X.018*%
%ADD74R,.028X.032*%
%ADD69R,.01X.059*%
%ADD114R,.065X.024*%
%ADD111R,.046X.034*%
%ADD107R,.038X.024*%
%ADD94R,.02X.059*%
%ADD83R,.024X.028*%
%ADD81R,.054X.026*%
%ADD72R,.016X.036*%
%ADD27C,.125*%
%ADD18R,.054X.044*%
%ADD118R,.049X.014*%
%ADD90R,.027X.018*%
%ADD71R,.044X.054*%
%ADD106R,.046X.062*%
%ADD101R,.018X.027*%
%ADD67R,.015X.084*%
%ADD96R,.071X.048*%
%ADD32R,.012X.079*%
%ADD112C,.237*%
%ADD66R,.015X.068*%
%ADD93R,.017X.067*%
%ADD16C,.238*%
%ADD15C,.256*%
%ADD78C,.178*%
%ADD25R,.046X.069*%
%AMMACRO122*
4,1,8,-.078,.0425,
-.078,-.0425,
.078,-.0425,
.078,.0425,
.0236,.0425,
.0236,.0145,
-.0236,.0145,
-.0236,.0425,
-.078,.0425,
0.0*
%
%ADD122MACRO122*%
%AMMACRO37*
4,1,28,.00052,-.00748,
.00052,-.00984,
.00603,-.00984,
.006705,-.009782,
.007359,-.009607,
.007974,-.009321,
.008529,-.008933,
.009009,-.008455,
.009398,-.0079,
.009685,-.007286,
.009861,-.006632,
.00992,-.005957,
.00992,-.00591,
.00992,.00591,
.009869,.006585,
.009701,.007242,
.009421,.007859,
.009039,.008418,
.008565,.008903,
.008015,.009297,
.007404,.009591,
.006751,.009773,
.006077,.00984,
.00603,.00984,
.00052,.00984,
.00052,.00748,
-.00991,.00748,
-.00991,-.00748,
.00052,-.00748,
0.0*
%
%ADD37MACRO37*%
%AMMACRO24*
4,1,28,.00748,.00052,
.00984,.00052,
.00984,.00603,
.009782,.006705,
.009607,.007359,
.009321,.007974,
.008933,.008529,
.008455,.009009,
.0079,.009398,
.007286,.009685,
.006632,.009861,
.005957,.00992,
.00591,.00992,
-.00591,.00992,
-.006585,.009869,
-.007242,.009701,
-.007859,.009421,
-.008418,.009039,
-.008903,.008565,
-.009297,.008015,
-.009591,.007404,
-.009773,.006751,
-.00984,.006077,
-.00984,.00603,
-.00984,.00052,
-.00748,.00052,
-.00748,-.00991,
.00748,-.00991,
.00748,.00052,
0.0*
%
%ADD24MACRO24*%
%ADD26R,.059X.079*%
%AMMACRO54*
4,1,5,-.01378,-.00098,
-.01378,.00492,
.01378,.00492,
.01378,-.00492,
-.00984,-.00492,
-.01378,-.00098,
0.0*
%
%ADD54MACRO54*%
%AMMACRO23*
4,1,28,-.00051,-.00748,
-.00051,-.00984,
-.00602,-.00984,
-.006695,-.009782,
-.007349,-.009607,
-.007964,-.009321,
-.008519,-.008933,
-.008998,-.008455,
-.009388,-.0079,
-.009675,-.007287,
-.009851,-.006632,
-.00991,-.005958,
-.00991,-.00591,
-.00991,.00591,
-.009859,.006585,
-.009691,.007242,
-.009411,.007859,
-.009029,.008418,
-.008555,.008903,
-.008005,.009297,
-.007394,.00959,
-.006742,.009773,
-.006068,.00984,
-.00602,.00984,
-.00051,.00984,
-.00051,.00748,
.00992,.00748,
.00992,-.00748,
-.00051,-.00748,
0.0*
%
%ADD23MACRO23*%
%AMMACRO22*
4,1,28,.00748,-.00051,
.00984,-.00051,
.00984,-.00602,
.009782,-.006695,
.009607,-.007349,
.009321,-.007964,
.008933,-.008519,
.008455,-.008998,
.0079,-.009388,
.007287,-.009675,
.006632,-.009851,
.005958,-.00991,
.00591,-.00991,
-.00591,-.00991,
-.006585,-.009859,
-.007242,-.009691,
-.007859,-.009411,
-.008418,-.009029,
-.008903,-.008555,
-.009297,-.008005,
-.00959,-.007394,
-.009773,-.006742,
-.00984,-.006068,
-.00984,-.00602,
-.00984,-.00051,
-.00748,-.00051,
-.00748,.00992,
.00748,.00992,
.00748,-.00051,
0.0*
%
%ADD22MACRO22*%
%AMMACRO42*
4,1,5,-.00098,.01378,
.00492,.01378,
.00492,-.01378,
-.00492,-.01378,
-.00492,.00984,
-.00098,.01378,
0.0*
%
%ADD42MACRO42*%
%AMMACRO53*
4,1,5,-.01378,.00098,
-.01378,-.00492,
.01378,-.00492,
.01378,.00492,
-.00984,.00492,
-.01378,.00098,
0.0*
%
%ADD53MACRO53*%
%AMMACRO55*
4,1,5,.00098,.01378,
-.00492,.01378,
-.00492,-.01378,
.00492,-.01378,
.00492,.00984,
.00098,.01378,
0.0*
%
%ADD55MACRO55*%
%ADD127C,.01*%
%ADD128C,.011*%
%ADD129C,.012*%
%ADD130C,.014*%
%ADD131C,.015*%
%ADD132C,.004*%
%ADD133C,.006*%
%ADD134C,.0051*%
%ADD135C,.007*%
%ADD136C,.008*%
%ADD137C,.0045*%
%ADD138C,.0054*%
%ADD139C,.0046*%
%ADD140C,.0056*%
%ADD141C,.03004*%
G75*
%LPD*%
G75*
G36*
G01X331081Y468024D02*
X332262D01*
X332646Y467640D01*
Y451968D01*
G03X336614Y448000I3969J1D01*
G01X346457D01*
G02X352331Y442126I0J-5874D01*
G01Y336646D01*
X345472D01*
G03X341504Y332678I0J-3968D01*
G01Y322834D01*
G03X345472Y318866I3968J0D01*
G01X352331D01*
Y7874D01*
G02X346457Y2000I-5874J0D01*
G01X7874D01*
G02X2000Y7874I0J5874D01*
G01Y318866D01*
X8858D01*
G03X12827Y322835I0J3969D01*
G01Y332677D01*
G03X8858Y336646I-3969J0D01*
G01X2000D01*
Y442126D01*
G02X7874Y448000I5874J0D01*
G01X17717D01*
G03X21685Y451968I-1J3969D01*
G01Y467365D01*
X22132Y467812D01*
X23372D01*
X23682Y467502D01*
Y451968D01*
G02X17717Y446002I-5966J0D01*
G01X7874D01*
G03X3998Y442126I0J-3876D01*
G01Y338644D01*
X8858D01*
G02X14824Y332677I-1J-5967D01*
G01Y322833D01*
G02X8858Y316868I-5966J1D01*
G01X3998D01*
Y15500D01*
X4971Y14527D01*
X53737D01*
X58140Y10124D01*
Y5858D01*
X60000Y3998D01*
X346457D01*
G03X350334Y7874I0J3877D01*
G01Y316868D01*
X345472D01*
G02X339506Y322834I0J5967D01*
G01Y332678D01*
G02X345472Y338644I5966J-1D01*
G01X350334D01*
Y442126D01*
G03X346459Y446002I-3876J0D01*
G01X336614D01*
G02X330648Y451968I0J5966D01*
G01Y467591D01*
X331081Y468024D01*
G37*
G36*
G01X5900Y220700D02*
X22400D01*
X22498Y220602D01*
Y205662D01*
X23955Y204205D01*
Y191880D01*
X23856Y191782D01*
X20305D01*
X20292Y191768D01*
X20248D01*
X19490Y191010D01*
Y190250D01*
X18720Y189480D01*
X15415D01*
X15394Y189458D01*
X15329D01*
X14731Y188860D01*
Y188795D01*
X14608Y188673D01*
Y186125D01*
X14731Y186003D01*
Y125503D01*
X15466Y124768D01*
X16266D01*
X16321Y124712D01*
X17483D01*
X17491Y124704D01*
X53442D01*
X54056Y124090D01*
Y119682D01*
X53422Y119048D01*
X6304D01*
X5398Y119954D01*
Y220198D01*
X5900Y220700D01*
G37*
G36*
G01X17133Y152691D02*
X51843D01*
X53180Y151354D01*
Y125988D01*
X52898Y125706D01*
X17906D01*
X17898Y125714D01*
X16741D01*
X16686Y125770D01*
X16680D01*
X16165Y126285D01*
Y151723D01*
X17133Y152691D01*
G37*
G36*
G01X20729Y190766D02*
X20741Y190780D01*
X23660D01*
X23885Y190555D01*
Y189300D01*
X20903Y186318D01*
X15832D01*
X15732Y186418D01*
Y186420D01*
X15610Y186542D01*
Y188256D01*
X15812Y188456D01*
X15823D01*
X15843Y188478D01*
X19298D01*
X20630Y189810D01*
Y190690D01*
X20706Y190766D01*
X20729D01*
G37*
G36*
G01X24856Y228344D02*
X25700Y227500D01*
Y224500D01*
X24600Y223400D01*
X15500D01*
X14800Y224100D01*
Y230000D01*
X15900Y231100D01*
X18700D01*
X21456Y228344D01*
X24856D01*
G37*
G36*
G01X6221Y315017D02*
X27183D01*
X28600Y313600D01*
X49892D01*
X51300Y312192D01*
Y307786D01*
X50986Y307472D01*
X49938D01*
G03X49548Y307429I-4J-1751D01*
G01X49526Y307424D01*
X14312D01*
X14311Y307422D01*
X12032D01*
X11996Y307386D01*
X11739D01*
X10600Y306247D01*
Y286269D01*
X13163Y283706D01*
Y255166D01*
X14622Y253707D01*
X22875D01*
X23685Y254517D01*
X26655D01*
X27235Y253937D01*
Y249127D01*
X28160Y248202D01*
Y231300D01*
X27760Y230900D01*
X20326D01*
X19048Y232178D01*
X6022D01*
X5534Y232666D01*
Y314330D01*
X6221Y315017D01*
G37*
G36*
G01X14931Y306422D02*
X51178D01*
X51319Y306281D01*
Y289000D01*
X48781Y286462D01*
X48220D01*
X48219Y286461D01*
X13361D01*
X11867Y287955D01*
Y305841D01*
X12411Y306384D01*
X12447Y306420D01*
X14930D01*
X14931Y306422D01*
G37*
G36*
G01X16600Y418900D02*
X21000D01*
X22100Y420000D01*
Y431200D01*
X21650Y431650D01*
X16950D01*
X16300Y431000D01*
Y426100D01*
Y419200D01*
X16600Y418900D01*
G37*
G36*
G01X26025Y195535D02*
X26030Y195540D01*
X27110D01*
X27130Y195520D01*
Y193763D01*
X27105Y193738D01*
X27215Y193628D01*
Y183525D01*
X28580Y182160D01*
X28590D01*
X28730Y182020D01*
X38161D01*
X39178Y183037D01*
Y183111D01*
X39180Y183112D01*
Y185160D01*
X39342Y185322D01*
X41108D01*
X42092Y184339D01*
Y167745D01*
X41412Y167065D01*
X20435D01*
X19882Y167618D01*
Y181868D01*
X23311Y185296D01*
X26025Y188010D01*
Y195535D01*
G37*
G36*
G01X31300Y190690D02*
X34212D01*
X34910Y189992D01*
Y188263D01*
X38178Y184995D01*
Y183527D01*
X37967Y183316D01*
X36115D01*
X35904Y183527D01*
Y184404D01*
X34758Y185550D01*
X34754Y185626D01*
G03X34243Y186763I-1748J-102D01*
G01X33158Y187848D01*
G03X32021Y188359I-1239J-1237D01*
G01X31945Y188363D01*
X31300Y189008D01*
Y190690D01*
G37*
G36*
G01X28365Y185808D02*
Y194290D01*
Y197415D01*
X27890Y197890D01*
X25660D01*
X25123Y198427D01*
Y205217D01*
X23598Y206742D01*
Y220583D01*
X23608Y220593D01*
X25420Y222405D01*
X28200Y225185D01*
Y226770D01*
Y227400D01*
X28300Y227500D01*
X31500D01*
X31600Y227400D01*
Y219415D01*
X29585Y217400D01*
Y208313D01*
Y206338D01*
Y203160D01*
Y186315D01*
X30940Y184960D01*
Y183330D01*
X30780Y183170D01*
X29070D01*
X28376Y183864D01*
Y185796D01*
X28365Y185808D01*
G37*
G36*
G01X30202Y255122D02*
X30246Y255167D01*
X31205D01*
X31305Y255067D01*
Y252341D01*
X31289Y252304D01*
G03X31172Y251721I1384J-581D01*
G01Y249228D01*
G03X31304Y248611I1501J-1D01*
G01X31322Y248571D01*
Y247015D01*
X34718Y243618D01*
X36182D01*
X39400Y240400D01*
Y238600D01*
X37187Y236387D01*
Y224827D01*
X36838Y224478D01*
X33593D01*
X33379Y224692D01*
Y227121D01*
X29162Y231338D01*
Y248256D01*
X30202Y249296D01*
Y255122D01*
G37*
G36*
G01X26505Y256667D02*
Y255777D01*
X26345Y255617D01*
X23135D01*
X22260Y254742D01*
X19560D01*
X19305Y254997D01*
Y255967D01*
Y256637D01*
X19435Y256767D01*
X23805D01*
X26405D01*
X26505Y256667D01*
G37*
G36*
G01X21500Y276200D02*
X35200D01*
X35600Y275800D01*
Y267495D01*
X35200Y267095D01*
X29295D01*
X28800Y266600D01*
Y263700D01*
X29205Y263295D01*
Y261763D01*
G03X29204Y261700I1500J-55D01*
G01Y258413D01*
G03X29205Y258350I1501J-8D01*
G01Y255535D01*
X29200Y255530D01*
Y250012D01*
X29055Y249867D01*
X28415D01*
X28295Y249987D01*
Y260527D01*
X27211Y261611D01*
X25406D01*
X24300Y262717D01*
X21955D01*
X21205Y263467D01*
Y275905D01*
X21500Y276200D01*
G37*
G36*
G01X35600Y416500D02*
Y411200D01*
X30100Y405700D01*
X20700D01*
X20200Y406200D01*
Y412400D01*
X20700Y412900D01*
X26200D01*
X29600Y416300D01*
Y425900D01*
X29900Y426200D01*
X35100D01*
X35600Y425700D01*
Y416500D01*
G37*
G36*
G01X45200Y228800D02*
X42000Y232000D01*
X39500D01*
X38389Y230889D01*
Y219811D01*
X39023Y219177D01*
X43177D01*
X45200Y221200D01*
Y228800D01*
G37*
G36*
G01X43431Y265000D02*
X46000D01*
X46246Y264754D01*
Y254684D01*
X45710Y254148D01*
X40256D01*
X39260Y255145D01*
G03X38997Y255355I-1063J-1061D01*
G01X38977Y255367D01*
X38842Y255502D01*
X38690D01*
X38660Y255512D01*
G03X38198Y255584I-459J-1429D01*
G01X36414D01*
G03X35952Y255512I-3J-1501D01*
G01X35922Y255502D01*
X35010D01*
X34910Y255602D01*
Y256502D01*
X35010Y256602D01*
X39110D01*
X40535Y258027D01*
X42571D01*
X42975Y258431D01*
Y263982D01*
G03X43231Y264800I-1175J817D01*
G02X43431Y265000I200J0D01*
G37*
G36*
G01X38828Y468024D02*
X40009D01*
X40382Y467651D01*
Y451968D01*
G03X44350Y448000I3969J1D01*
G01X45976D01*
X46336Y447640D01*
Y446364D01*
X45974Y446002D01*
X44350D01*
G02X38384Y451968I0J5966D01*
G01Y467580D01*
X38828Y468024D01*
G37*
G36*
G01X60700Y278100D02*
X66000D01*
X66098Y278002D01*
Y275685D01*
X67385Y274398D01*
X72015D01*
X72615Y274998D01*
X75401D01*
X75798Y274601D01*
Y273885D01*
X75900Y273784D01*
Y272900D01*
X76700Y272100D01*
X77200D01*
X77498Y271801D01*
Y271385D01*
X77600Y271284D01*
Y269250D01*
X77017Y268667D01*
X76881Y268754D01*
G03X76213Y268952I-670J-1034D01*
G01X64048D01*
X60200Y272800D01*
Y277600D01*
X60700Y278100D01*
G37*
G36*
G01X56894Y450344D02*
G03I-412J0D01*
G37*
G36*
G01X63012Y450700D02*
G03I-412J0D01*
G37*
G36*
G01X67700Y93277D02*
X69900Y95477D01*
X96023D01*
X97500Y94000D01*
X100500D01*
X100850Y93650D01*
Y90850D01*
X98500Y88500D01*
Y83500D01*
X97000Y82000D01*
X68700D01*
X67700Y83000D01*
Y93277D01*
G37*
G36*
G01X75616Y127886D02*
X75700Y127970D01*
X76485D01*
X76544Y127911D01*
Y121654D01*
X79059Y119139D01*
Y116147D01*
X79965Y115241D01*
X87059D01*
X87500Y114800D01*
X89600D01*
X89900Y114500D01*
Y106000D01*
X89788Y105888D01*
X70484D01*
X70281Y106090D01*
Y118451D01*
X71798Y119968D01*
X73089D01*
G03X73548Y120040I0J1502D01*
G01X73578Y120050D01*
X74727D01*
X75616Y120939D01*
Y127886D01*
G37*
G36*
G01X77611Y124534D02*
Y122402D01*
Y122164D01*
X79092Y120683D01*
X80070Y119705D01*
Y117189D01*
X80273Y116986D01*
X80488D01*
X82033D01*
X82333Y117286D01*
Y119415D01*
X81030Y120718D01*
X78887Y122861D01*
Y124109D01*
X78352Y124644D01*
X77721D01*
X77611Y124534D01*
G37*
G36*
G01X65816Y157464D02*
X68336D01*
X69800Y156000D01*
X74284D01*
X74285Y155998D01*
X76902D01*
X77098Y155802D01*
Y153515D01*
X75354Y151771D01*
Y151754D01*
X75260Y151660D01*
Y129388D01*
X74624Y128752D01*
Y128310D01*
X74614Y128301D01*
Y126476D01*
X74396Y126258D01*
X73312D01*
X73084Y126486D01*
Y128890D01*
X72296Y129678D01*
X72256D01*
Y130667D01*
G03X71754Y131168I-501J0D01*
G01X71476D01*
X71417Y131227D01*
G03X70354Y131668I-1063J-1061D01*
G01X68955D01*
X67852Y132772D01*
G03X67364Y133097I-1060J-1063D01*
G01X67358Y133099D01*
X67100Y133357D01*
Y150991D01*
X65391Y152700D01*
Y157039D01*
X65816Y157464D01*
G37*
G36*
G01X79100Y157300D02*
X81900D01*
X83498Y155702D01*
Y153085D01*
X83500Y153084D01*
Y153000D01*
X87554Y148946D01*
Y145954D01*
X84400Y142800D01*
Y140500D01*
X78893Y134993D01*
Y126616D01*
X78770Y126493D01*
X77665D01*
X77557Y126601D01*
Y128755D01*
X76356Y129956D01*
Y151356D01*
X78100Y153100D01*
Y156300D01*
X79100Y157300D01*
G37*
G36*
G01X87300Y152300D02*
X88000Y153000D01*
Y161500D01*
X86400Y163100D01*
X78700D01*
X74400Y158800D01*
Y157300D01*
X74700Y157000D01*
X77100D01*
X79000Y158900D01*
X82000D01*
X84500Y156400D01*
Y153500D01*
X85700Y152300D01*
X87300D01*
G37*
G36*
G01X70142Y292300D02*
X72100D01*
X72500Y291900D01*
Y283800D01*
X73400Y282900D01*
X74993D01*
G03X75960Y282547I967J1148D01*
G03X76798Y282802I1J1502D01*
G01X79339Y280261D01*
X80482Y277501D01*
G03X80800Y276963I2061J855D01*
G01Y272982D01*
X80207Y272389D01*
G03X79720Y271656I1579J-1577D01*
G01X79500D01*
G03X78878Y271568I-2J-2231D01*
G01X78765Y271535D01*
X78500Y271800D01*
Y272600D01*
X76800Y274300D01*
Y275600D01*
X76400Y276000D01*
X72200D01*
X71600Y275400D01*
X67800D01*
X67100Y276100D01*
Y282820D01*
X67118Y282859D01*
G03X67232Y283375I-1118J518D01*
G01Y290490D01*
X67810Y291068D01*
X68400D01*
G03X69271Y291429I0J1231D01*
G01X70142Y292300D01*
G37*
G36*
G01X76413Y313045D02*
X86824D01*
X89378Y310490D01*
Y299210D01*
X87160Y296992D01*
X82553D01*
G03X82068Y296907I1J-1432D01*
G01X82035Y296895D01*
X75182D01*
X74959Y297118D01*
X75571Y297729D01*
G03X75932Y298600I-870J871D01*
G01Y302500D01*
G03X75571Y303371I-1231J0D01*
G01X74516Y304426D01*
Y311148D01*
X76413Y313045D01*
G37*
G36*
G01X87680Y128760D02*
X89260D01*
X89770Y128250D01*
Y124630D01*
X89040Y123900D01*
X85223D01*
X83801Y125323D01*
G03X83632Y125468I-1060J-1064D01*
G01X83500Y125600D01*
X83420D01*
X83379Y125619D01*
G03X82739Y125762I-639J-1358D01*
G01X81772D01*
G03X81132Y125619I-1J-1501D01*
G01X81091Y125600D01*
X80400D01*
X80300Y125700D01*
Y126700D01*
X80400Y126800D01*
X81223D01*
X81256Y126788D01*
G03X81772Y126696I518J1410D01*
G01X84098D01*
G03X84360Y126719I0J1502D01*
G01X84462Y126738D01*
X84800Y126400D01*
X85320D01*
X87680Y128760D01*
G37*
G36*
G01X85908Y445550D02*
G03I-632J0D01*
G37*
G36*
G01X82888Y445597D02*
G03I-632J0D01*
G37*
G36*
G01X92633Y450402D02*
G03I-632J0D01*
G37*
G36*
G01X109200Y97300D02*
X113400D01*
X114300Y96400D01*
X114523D01*
X114808Y96115D01*
Y94900D01*
G03X114943Y94227I1752J1D01*
G01X114958Y94190D01*
Y93300D01*
G03X115460Y92798I502J0D01*
G01X117660D01*
G03X118162Y93300I0J502D01*
G01Y94190D01*
X118177Y94227D01*
G03X118312Y94900I-1617J674D01*
G01Y96400D01*
X119500D01*
X120200Y97100D01*
X123000D01*
X124200Y95900D01*
Y87112D01*
X123678D01*
G03X122100Y86458I0J-2231D01*
G01X118174Y82532D01*
X114570D01*
G03X113620Y82319I1J-2232D01*
G01X113579Y82300D01*
X112700D01*
X112309Y82691D01*
X112294Y82721D01*
G03X111621Y83394I-1344J-671D01*
G01X111591Y83409D01*
X108300Y86700D01*
X108154D01*
X108102Y86738D01*
G03X106800Y87156I-1300J-1814D01*
G01X105400D01*
Y89466D01*
X105789Y90406D01*
X105930Y90400D01*
G03X106000Y90398I78J1500D01*
G03X107502Y91900I0J1502D01*
G03X107300Y92652I-1501J0D01*
G01Y94055D01*
X107484Y94498D01*
G03X107654Y95352I-2062J854D01*
G03X107636Y95627I-2231J-8D01*
G01X107624Y95724D01*
X109200Y97300D01*
G37*
G36*
G01X98020Y335534D02*
G03I-412J0D01*
G37*
G36*
G01X97788Y450437D02*
G03I-632J0D01*
G37*
G36*
G01X128788Y212781D02*
X134002D01*
X134501Y212282D01*
Y209434D01*
X135101Y208834D01*
X139890D01*
X141001Y209945D01*
Y225201D01*
X141200Y225400D01*
X147301D01*
X147601Y225100D01*
Y207131D01*
X146516Y206046D01*
X142748D01*
X142226Y205524D01*
X129729D01*
X128503Y206750D01*
Y207223D01*
Y212496D01*
X128788Y212781D01*
G37*
G36*
G01X136501Y216634D02*
X139101D01*
X139501Y216234D01*
Y210634D01*
X139001Y210134D01*
X136801D01*
X136401Y210534D01*
Y216534D01*
X136501Y216634D01*
G37*
G36*
G01X127918Y222634D02*
X139602D01*
X139901Y222334D01*
Y218134D01*
X139701Y217934D01*
X136212D01*
X134528Y216250D01*
Y215558D01*
X133873Y214903D01*
X128100D01*
X127200Y215803D01*
Y221915D01*
X127918Y222634D01*
G37*
G36*
G01X128082Y226110D02*
X139522D01*
X140000Y225632D01*
Y223662D01*
X139973Y223635D01*
X127875D01*
X127530Y223980D01*
Y225119D01*
X127544Y225155D01*
G03X127631Y225581I-1144J456D01*
G01X127633Y225661D01*
X128082Y226110D01*
G37*
G36*
G01X138400Y292200D02*
X141900D01*
X144300Y289800D01*
Y282477D01*
X143892Y282068D01*
G03X143378Y280830I1237J-1239D01*
G01Y277600D01*
X139226D01*
X138572Y278254D01*
X138560Y278315D01*
G03X137083Y279547I-1477J-269D01*
G03X135598Y278270I0J-1502D01*
G01X135572Y278100D01*
X134500D01*
X134498Y278102D01*
Y280833D01*
G03X134398Y281320I-1231J1D01*
G01X134345Y281445D01*
X135200Y282300D01*
X136300D01*
X138100Y284100D01*
Y290700D01*
X138200Y290800D01*
Y292000D01*
X138400Y292200D01*
G37*
G36*
G01X127712Y392600D02*
G03I-412J0D01*
G37*
G36*
G01X153247Y133400D02*
X158420D01*
X158452Y133389D01*
G03X158926Y133300I548J1611D01*
G01X159003Y133297D01*
X160040Y132260D01*
Y123840D01*
X160460Y123420D01*
Y121540D01*
X160060Y121140D01*
X151970D01*
X151203Y121907D01*
Y132407D01*
X151514Y132718D01*
X152565D01*
X153247Y133400D01*
G37*
G36*
G01X148240Y143060D02*
X150190D01*
X150404Y142846D01*
Y141293D01*
X150540Y141157D01*
Y141088D01*
X151150Y140478D01*
X153254D01*
X153336Y140396D01*
Y139053D01*
X152098Y137815D01*
Y136185D01*
X152446Y135838D01*
Y135649D01*
X152703Y135392D01*
Y134272D01*
X152150Y133719D01*
X148221D01*
X143570Y138370D01*
X140680D01*
X140400Y138650D01*
Y141050D01*
X140990Y141640D01*
X146820D01*
X148240Y143060D01*
G37*
G36*
G01X151681Y143490D02*
X157710D01*
X157895Y143305D01*
Y142278D01*
X157797Y142180D01*
G03X157298Y140977I1203J-1204D01*
G01Y135000D01*
G03X157300Y134927I1702J10D01*
G02X156900Y134510I-400J-17D01*
G01X155190D01*
X153100Y136600D01*
Y137400D01*
X154338Y138638D01*
Y141175D01*
X154032Y141481D01*
X151632D01*
X151405Y141708D01*
Y143214D01*
X151681Y143490D01*
G37*
G36*
G01X147538Y151254D02*
X160031D01*
G02X160424Y150780I0J-400D01*
G03X160398Y150500I1476J-278D01*
G03X161442Y149070I1501J0D01*
G01X161581Y149025D01*
Y144755D01*
X161320Y144494D01*
X155709D01*
X155449Y144754D01*
Y144941D01*
X155450Y144950D01*
G03X155456Y145086I-1496J134D01*
G03X155450Y145222I-1502J2D01*
G01X155449Y145231D01*
Y146050D01*
X154935Y146564D01*
X154222D01*
X154205Y146567D01*
G03X153954Y146588I-250J-1481D01*
G03X153703Y146567I-1J-1502D01*
G01X153686Y146564D01*
X150423D01*
X150406Y146567D01*
G03X150155Y146588I-250J-1481D01*
G03X149904Y146567I-1J-1502D01*
G01X149887Y146564D01*
X147987D01*
X147275Y147276D01*
Y150991D01*
X147538Y151254D01*
G37*
G36*
G01X149001Y220734D02*
X152148D01*
X153959Y218923D01*
G03X154304Y218681I869J872D01*
G01X154335Y218666D01*
X154778Y218222D01*
Y218210D01*
X154792D01*
X154813Y218188D01*
X157243D01*
X157248Y218193D01*
X157996D01*
X158101Y218088D01*
Y208090D01*
X156200Y206189D01*
X149052D01*
X148701Y206540D01*
Y220434D01*
X149001Y220734D01*
G37*
G36*
G01X148810Y230310D02*
X156666D01*
X156705Y230293D01*
G03X157500Y230124I794J1782D01*
G03X158119Y230224I2J1951D01*
G01X158236Y230264D01*
X158500Y230000D01*
Y228500D01*
X157562Y227562D01*
Y227390D01*
X157560Y227389D01*
Y222869D01*
X157424Y222732D01*
X153957D01*
X153120Y223569D01*
X152822D01*
X152797Y223576D01*
G03X152433Y223622I-360J-1386D01*
G01X150467D01*
G03X150103Y223576I-4J-1432D01*
G01X150078Y223569D01*
X148691D01*
X148606Y223654D01*
Y225500D01*
X148602Y225504D01*
Y225515D01*
X148500Y225617D01*
Y230000D01*
X148810Y230310D01*
G37*
G36*
G01X140712Y395100D02*
G03I-412J0D01*
G37*
G36*
G01X165117Y93991D02*
G03I-688J0D01*
G37*
G36*
G01X159561Y93976D02*
G03I-688J0D01*
G37*
G36*
G01X158562Y226974D02*
X158732Y227144D01*
X158982Y227394D01*
X160106D01*
X160582Y226918D01*
X160982Y225784D01*
Y222892D01*
X160821Y222731D01*
X158666D01*
X158562Y222835D01*
Y226974D01*
G37*
G36*
G01X157312Y385700D02*
G03I-412J0D01*
G37*
G36*
G01X157694Y389102D02*
G03I-412J0D01*
G37*
G36*
G01X164730D02*
G03I-412J0D01*
G37*
G36*
G01X174541Y93991D02*
G03I-688J0D01*
G37*
G36*
G01X168985Y93976D02*
G03I-688J0D01*
G37*
G36*
G01X181021Y114292D02*
G03I-688J0D01*
G37*
G36*
G01X177494Y387402D02*
G03I-412J0D01*
G37*
G36*
G01X194200Y89300D02*
X194800Y89900D01*
X199400D01*
X200200Y89100D01*
Y68600D01*
X199300Y67700D01*
X187300D01*
X185700Y69300D01*
Y79100D01*
X186600Y80000D01*
X193000D01*
X194200Y81200D01*
Y89300D01*
G37*
G36*
G01X184530Y387402D02*
G03I-412J0D01*
G37*
G36*
G01X206500Y83400D02*
X222400D01*
X222849Y82951D01*
X222862Y82893D01*
G03X223100Y82348I1468J317D01*
G01Y78200D01*
X221300Y76400D01*
Y68800D01*
X219700Y67200D01*
X207000D01*
X205900Y68300D01*
Y82800D01*
X206500Y83400D01*
G37*
G36*
G01X218502Y95200D02*
X223100D01*
X223900Y94400D01*
Y90600D01*
X223200Y89900D01*
Y85900D01*
X222100Y84800D01*
X205300D01*
X203900Y86200D01*
Y89500D01*
X204300Y89900D01*
X210700D01*
X213000Y92200D01*
X215500D01*
X216088Y92788D01*
X216091Y92790D01*
G03X216138Y92837I-1215J1262D01*
G01X218502Y95200D01*
G37*
G36*
G01X198969Y101286D02*
G03I-688J0D01*
G37*
G36*
G01X218793Y115469D02*
X222845D01*
X223062Y115252D01*
Y111563D01*
X222249Y110750D01*
X206519D01*
X206202Y111067D01*
Y111679D01*
X207775Y113252D01*
X215954D01*
G03X217016Y113691I1J1501D01*
G01X218793Y115469D01*
G37*
G36*
G01X203592Y416371D02*
G03I-412J0D01*
G37*
G36*
G01X212277Y444520D02*
G03I-412J0D01*
G37*
G36*
G01X222637Y407650D02*
G03I-412J0D01*
G37*
G36*
G01X217137D02*
G03I-412J0D01*
G37*
G36*
G01X218497Y444520D02*
G03I-412J0D01*
G37*
G36*
G01X239191Y235654D02*
G03I-561J0D01*
G37*
G36*
G01X255950Y267370D02*
X259670D01*
X260200Y266840D01*
Y265660D01*
X259728Y265188D01*
X259634Y265196D01*
G03X259500Y265202I-134J-1496D01*
G03X258790Y265024I-1J-1502D01*
G01X258746Y265000D01*
X258600D01*
X257870Y264270D01*
Y263270D01*
X256570Y261970D01*
X252020D01*
X251840Y262150D01*
Y264910D01*
X253090Y266160D01*
X254740D01*
X255950Y267370D01*
G37*
G36*
G01X246612Y299700D02*
G03I-412J0D01*
G37*
G36*
G01X245712Y445800D02*
G03I-412J0D01*
G37*
G36*
G01X262318Y119720D02*
X265323D01*
X269071Y115972D01*
X271200D01*
X273250Y113922D01*
Y111050D01*
X272100Y109900D01*
X268738D01*
X267150Y111488D01*
Y111510D01*
X267129D01*
X266800Y111838D01*
X264289D01*
X263901Y112226D01*
Y113389D01*
X262173Y115117D01*
Y119575D01*
X262318Y119720D01*
G37*
G36*
G01X265606Y154576D02*
X269228D01*
X269615Y154189D01*
Y146340D01*
G02X269171Y145943I-400J0D01*
G03X269004Y145952I-164J-1493D01*
G03X267502Y144450I0J-1502D01*
G03X267872Y143463I1501J0D01*
G02Y142937I-302J-263D01*
G03X267502Y141950I1131J-987D01*
G03X268516Y140529I1503J0D01*
G02X268619Y139826I-130J-378D01*
G03X267991Y138604I875J-1222D01*
G03X269493Y137102I1502J0D01*
G03X270975Y138360I0J1502D01*
G01X270986Y138424D01*
X271172Y138611D01*
X271455Y138328D01*
X279690D01*
X281751Y136267D01*
X288803D01*
X289668Y137132D01*
Y139638D01*
X289791Y139761D01*
X292907D01*
X292905Y139759D01*
X293989Y138675D01*
Y133582D01*
X293608Y133202D01*
X287954D01*
G03X287322Y133062I1J-1502D01*
G01X287282Y133044D01*
X285295D01*
G03X284788Y132955I2J-1502D01*
G01X284755Y132944D01*
X284706D01*
G03X284471Y132914I-6J-890D01*
G01X284446Y132907D01*
X280275D01*
X278113Y135069D01*
X261776D01*
X260558Y136286D01*
Y149528D01*
X261141Y150111D01*
G02X261761Y150042I282J-283D01*
G03X263030Y149344I1269J805D01*
G03X264532Y150846I0J1502D01*
G03X264248Y151724I-1502J-1D01*
G02X264304Y152254I325J234D01*
G03X264796Y153366I-1011J1112D01*
G03X264774Y153624I-1502J2D01*
G01X264756Y153726D01*
X265606Y154576D01*
G37*
G36*
G01X270059Y129571D02*
X278108D01*
X278323Y129356D01*
Y128239D01*
X278276Y128193D01*
Y122016D01*
X277850Y121590D01*
X274185D01*
X272750Y123025D01*
X272257D01*
X272222Y123038D01*
G03X271602Y123152I-622J-1638D01*
G03X270982Y123038I2J-1752D01*
G01X270947Y123025D01*
X270587D01*
X269618Y123994D01*
Y129130D01*
X270059Y129571D01*
G37*
G36*
G01X284070Y137570D02*
X283895Y137395D01*
X282110D01*
X280171Y139334D01*
X272009D01*
X270663Y140680D01*
Y146142D01*
X270823Y146302D01*
X278101D01*
X278102Y146301D01*
X281497D01*
X284070Y143728D01*
Y137570D01*
G37*
G36*
G01X271232Y151967D02*
X289146D01*
X289664Y151449D01*
G03X290008Y151102I1224J870D01*
G01X290021Y151092D01*
X290118Y150995D01*
Y145874D01*
X290008Y145763D01*
X289927Y145682D01*
X283546D01*
X281936Y147292D01*
X281922D01*
X281912Y147302D01*
X278517D01*
X278516Y147304D01*
X270844D01*
X270638Y147509D01*
Y151374D01*
X271232Y151967D01*
G37*
G36*
G01X269071Y179088D02*
G03I-561J0D01*
G37*
G36*
G01X263441Y178977D02*
G03I-561J0D01*
G37*
G36*
G01X268952Y207262D02*
G03I-561J0D01*
G37*
G36*
G01X260830Y207358D02*
G03I-561J0D01*
G37*
G36*
G01X269952Y214593D02*
G03I-561J0D01*
G37*
G36*
G01X261830Y214657D02*
G03I-561J0D01*
G37*
G36*
G01X270640Y247915D02*
Y252171D01*
X270972Y252503D01*
X273083D01*
X273391Y252195D01*
Y247856D01*
X273189Y247654D01*
X270901D01*
X270640Y247915D01*
G37*
G36*
G01X266612Y300500D02*
G03I-412J0D01*
G37*
G36*
G01X271912Y446800D02*
G03I-412J0D01*
G37*
G36*
G01X266712Y435900D02*
G03I-412J0D01*
G37*
G36*
G01X282500Y124500D02*
Y118250D01*
X282250Y118000D01*
X279500D01*
X276400D01*
X276100Y118300D01*
Y119800D01*
X276300Y120000D01*
X278778D01*
X279278Y120500D01*
Y121238D01*
Y121838D01*
Y123538D01*
Y127778D01*
X279500Y128000D01*
X281500D01*
X282000Y127500D01*
Y125000D01*
X282500Y124500D01*
G37*
G36*
G01X290355Y144694D02*
X291660D01*
X292991Y143363D01*
X292969Y143258D01*
G03X292934Y142907I1716J-348D01*
G01Y141838D01*
X292580Y141485D01*
X289931D01*
X288662Y140216D01*
Y139213D01*
X286853Y137404D01*
X285364D01*
X285084Y137684D01*
Y143766D01*
X285999Y144680D01*
X290342D01*
X290355Y144694D01*
G37*
G36*
G01X275251Y247650D02*
X274830Y248071D01*
Y251610D01*
X275546Y252326D01*
X280805D01*
X281255Y251876D01*
Y247894D01*
X281011Y247650D01*
X275251D01*
G37*
G36*
G01X276512Y381500D02*
G03I-412J0D01*
G37*
G36*
G01X285026Y387136D02*
G03I-412J0D01*
G37*
G36*
G01X272512Y396300D02*
G03I-412J0D01*
G37*
G36*
G01X281712Y419300D02*
G03I-412J0D01*
G37*
G36*
G01X278612Y408700D02*
G03I-412J0D01*
G37*
G36*
G01X295204Y152316D02*
X297919D01*
X297979Y152228D01*
G03X299139Y150668I18501J12546D01*
G01X299184Y150613D01*
Y145865D01*
X298424Y145105D01*
X292725D01*
X292345Y145485D01*
Y150583D01*
G02X292944Y150930I400J0D01*
G03X293693Y150730I749J1303D01*
G03X295192Y152130I0J1503D01*
G01X295204Y152316D01*
G37*
G36*
G01X297933Y196616D02*
G03I-561J0D01*
G37*
G36*
G01X301631Y231451D02*
X331751D01*
X333107D01*
X335561D01*
X339009D01*
X339147Y231313D01*
Y223467D01*
X338470Y222790D01*
X300928D01*
X300144Y223574D01*
Y229964D01*
X301631Y231451D01*
G37*
G36*
G01X308572Y251155D02*
X337638D01*
X339216Y249577D01*
Y232522D01*
X339146Y232452D01*
X301456D01*
X300041Y233867D01*
Y243313D01*
G03Y245713I-903J1200D01*
G01Y249293D01*
X301903Y251155D01*
X304160D01*
G03X305840I840J1244D01*
G01X306628D01*
G03X308572I972J1145D01*
G37*
G36*
G01X302200Y322900D02*
X306700D01*
X307000Y322600D01*
Y317600D01*
X306100Y316700D01*
Y310600D01*
X307500Y309200D01*
Y308000D01*
X306800Y307300D01*
X305500D01*
X303400D01*
X301200Y309500D01*
X300300D01*
X299300Y310500D01*
Y313800D01*
X301600Y316100D01*
Y322300D01*
X302200Y322900D01*
G37*
G36*
G01X295500Y338000D02*
X329500D01*
X332000Y335500D01*
Y319400D01*
X331800Y319200D01*
X328800D01*
X327600Y318000D01*
X323900D01*
X323500Y318400D01*
Y323000D01*
X321000Y325500D01*
X308500D01*
X306000Y328000D01*
X303775D01*
G02X303387Y328497I0J400D01*
G03X303402Y328618I-487J122D01*
G01Y332618D01*
G03X302900Y333120I-502J0D01*
G01X300100D01*
G03X299598Y332618I0J-502D01*
G01Y328618D01*
G03X299613Y328497I502J1D01*
G02X299225Y328000I-388J-97D01*
G01X296500D01*
X294500Y330000D01*
Y337000D01*
X295500Y338000D01*
G37*
G36*
G01X291212Y438300D02*
G03I-412J0D01*
G37*
G36*
G01X297132Y470576D02*
X298622D01*
Y461976D01*
X298628D01*
Y461726D01*
X298787Y461567D01*
X300018D01*
X300104Y461481D01*
Y448074D01*
X302618Y445560D01*
X328157D01*
X332423Y441294D01*
Y433584D01*
X332422Y433575D01*
G03X332386Y432809I8217J-770D01*
G03X332422Y432043I8253J4D01*
G01X332423Y432034D01*
Y427577D01*
X337347Y422653D01*
Y405939D01*
X336765Y405357D01*
X316528D01*
X314000Y407885D01*
Y430358D01*
X307933Y436426D01*
X296258D01*
X294768Y437916D01*
Y443840D01*
G03X295028Y444596I-972J757D01*
G01Y461423D01*
G03X294770Y462177I-1231J0D01*
G01Y470576D01*
X296260D01*
Y461976D01*
X296265D01*
Y461777D01*
X296391Y461651D01*
X297008D01*
X297132Y461775D01*
Y470576D01*
G37*
G36*
G01X290046Y470562D02*
X290060Y470576D01*
X291526D01*
X291534Y470566D01*
Y461968D01*
X292143Y461360D01*
G03X292279Y461198I1008J708D01*
G01X292564Y460913D01*
Y452762D01*
X292369Y452567D01*
X290403D01*
X290046Y452924D01*
Y470562D01*
G37*
G36*
G01X311719Y185534D02*
G03I-561J0D01*
G37*
G36*
G01X308978Y214178D02*
G03I-518J0D01*
G37*
G36*
G01X304501Y212664D02*
G03I-561J0D01*
G37*
G36*
G01X314664Y288630D02*
X314626Y288668D01*
Y288814D01*
X313294Y290146D01*
X312289D01*
X311155Y291280D01*
Y294415D01*
X311161Y294438D01*
G03X311202Y294789I-1461J349D01*
G03X311161Y295140I-1502J2D01*
G01X311155Y295163D01*
Y299989D01*
Y309855D01*
X312848Y311548D01*
X313710D01*
X320550D01*
X321024Y311074D01*
Y288318D01*
X320388Y287682D01*
Y287320D01*
X320380Y287313D01*
Y286233D01*
X320378Y286231D01*
Y285406D01*
X320160Y285188D01*
X319076D01*
X318848Y285416D01*
Y287820D01*
X318060Y288608D01*
X316371D01*
G03X316118Y288630I-256J-1480D01*
G01X314664D01*
G37*
G36*
G01X314385Y467812D02*
X315625D01*
X315966Y467471D01*
Y453751D01*
X315647Y453432D01*
X314431D01*
X313969Y453894D01*
Y467396D01*
X314385Y467812D01*
G37*
G36*
G01X322941Y123743D02*
Y127443D01*
X323241Y127743D01*
X327441D01*
X327641Y127543D01*
Y124054D01*
X329325Y122370D01*
X330017D01*
X330672Y121715D01*
Y116189D01*
Y115102D01*
X330658Y115088D01*
X330213Y114643D01*
X329126D01*
X327341D01*
X323433D01*
X322941Y115135D01*
Y123743D01*
G37*
G36*
G01X321825Y113792D02*
X321815Y113782D01*
X321565Y113532D01*
X320161D01*
X319807Y113886D01*
Y117994D01*
X319900Y118087D01*
X321689D01*
X321825Y117951D01*
Y113792D01*
G37*
G36*
G01X320102Y127842D02*
X321913D01*
X321940Y127815D01*
Y119384D01*
X321751Y119196D01*
X320108D01*
X319850Y119454D01*
Y127590D01*
X320102Y127842D01*
G37*
G36*
G01X320308Y135443D02*
X338641D01*
X340302D01*
X344940D01*
X346030Y134353D01*
Y116070D01*
X344503Y114543D01*
X340035D01*
X339193D01*
X338841D01*
X333130D01*
X332728Y114945D01*
Y121846D01*
X333225Y122343D01*
X336141D01*
X336741Y122943D01*
Y128243D01*
X336141Y128843D01*
X320408D01*
X320191Y129060D01*
Y135326D01*
X320308Y135443D01*
G37*
G36*
G01X324841Y136843D02*
Y140074D01*
X327100Y142333D01*
Y142337D01*
X328080Y143317D01*
Y145901D01*
X328587Y146408D01*
X338831D01*
X339341Y145898D01*
Y145243D01*
Y137143D01*
X338741Y136543D01*
X325141D01*
X324841Y136843D01*
G37*
G36*
G01X328941Y124343D02*
Y126943D01*
X329341Y127343D01*
X334941D01*
X335441Y126843D01*
Y124643D01*
X335041Y124243D01*
X329041D01*
X328941Y124343D01*
G37*
G36*
G01X321382Y286962D02*
X322264D01*
X322308Y286918D01*
Y274180D01*
X323858Y272630D01*
X331470D01*
X331700Y272400D01*
Y264300D01*
X331200Y263800D01*
X318100D01*
X317309Y264591D01*
Y275891D01*
X321380Y279961D01*
Y285816D01*
X321382Y285818D01*
Y286962D01*
G37*
G36*
G01X331524Y287400D02*
X335074D01*
X335098Y287394D01*
G03X335516Y287344I415J1701D01*
G01X336956D01*
X337500Y286800D01*
Y285800D01*
X336800Y285100D01*
X331400D01*
X331242Y284942D01*
X329997D01*
G03X329095Y284692I0J-1752D01*
G01X327536D01*
G03X327048Y284611I0J-1511D01*
G01X327016Y284600D01*
X326000D01*
X325900Y284700D01*
Y285600D01*
X326000Y285700D01*
X327071D01*
X327099Y285691D01*
G03X327536Y285626I437J1436D01*
G01X329129D01*
G03X329566Y285691I0J1501D01*
G01X329594Y285700D01*
X329700D01*
X329770Y285770D01*
X329799Y285784D01*
G03X330191Y286066I-670J1344D01*
G01X331524Y287400D01*
G37*
G36*
G01X323375Y282464D02*
Y280332D01*
Y280094D01*
Y277652D01*
X323354Y277631D01*
Y275060D01*
X323638Y274776D01*
X324291D01*
X325596D01*
X325740Y274920D01*
Y276591D01*
X324651Y277680D01*
Y280791D01*
Y282039D01*
Y283554D01*
X324382Y283823D01*
X323499D01*
X323375Y283699D01*
Y282464D01*
G37*
G36*
G01X323900Y315800D02*
X327500D01*
X328100Y315200D01*
Y314200D01*
X330140Y312160D01*
Y293340D01*
X329100Y292300D01*
X326049D01*
X324657Y290908D01*
Y285546D01*
X324534Y285423D01*
X323429D01*
X323321Y285531D01*
Y287685D01*
X322120Y288886D01*
Y314020D01*
X323900Y315800D01*
G37*
G36*
G01X325612Y383900D02*
G03I-412J0D01*
G37*
G36*
G01X335912Y363200D02*
G03I-412J0D01*
G37*
G36*
G01X336112Y376400D02*
G03I-412J0D01*
G37*
G36*
G01X375723Y-435380D02*
G03I-748J0D01*
G37*
G36*
G01X375414Y-218571D02*
G03I-748J0D01*
G37*
G36*
G01X375695Y-157108D02*
G03I-748J0D01*
G37*
G36*
G01X375414Y9701D02*
G03I-748J0D01*
G37*
G36*
G01X375656Y71164D02*
G03I-681J0D01*
G37*
G36*
G01X375347Y378973D02*
G03I-681J0D01*
G37*
G36*
G01X381350Y-435533D02*
G03I-748J0D01*
G37*
G36*
G01X381041Y-218724D02*
G03I-748J0D01*
G37*
G36*
G01X381322Y-157261D02*
G03I-748J0D01*
G37*
G36*
G01X381041Y9548D02*
G03I-748J0D01*
G37*
G36*
G01X381283Y71011D02*
G03I-681J0D01*
G37*
G36*
G01X380974Y378820D02*
G03I-681J0D01*
G37*
G36*
G01X396811Y-461442D02*
G03I-748J0D01*
G37*
G36*
G01X402438Y-461595D02*
G03I-748J0D01*
G37*
G36*
G01X402157Y-123786D02*
G03I-748J0D01*
G37*
G36*
G01X396530Y-123633D02*
G03I-748J0D01*
G37*
%LPC*%
G75*
G36*
G01X114943Y84778D02*
G02X114808Y85451I1617J674D01*
G01Y88651D01*
G02X118312I1752J0D01*
G01Y85451D01*
G02X118177Y84778I-1752J1D01*
G01X118162Y84741D01*
Y83851D01*
G02X117660Y83350I-502J1D01*
G01X115460D01*
G02X114958Y83851I-1J501D01*
G01Y84741D01*
X114943Y84778D01*
G37*
G54D141*
X76284Y280470D03*
%LPD*%
G75*
G54D100*
X166719Y73224D03*
G54D101*
Y70222D03*
G54D110*
X203211Y316159D03*
Y311041D03*
X210789Y316159D03*
Y313600D03*
Y311041D03*
G54D111*
X228832Y107236D03*
X220564D03*
Y113732D03*
X228832D03*
G54D102*
X162782Y73126D03*
X164751D03*
Y70074D03*
X162782D03*
X168687Y73126D03*
X170656D03*
Y70074D03*
X168687D03*
G54D120*
X325353Y132206D03*
G54D130*
G01X47294Y187525D02*
Y184491D01*
G01X45461Y191535D02*
X48035D01*
G01X46307Y206333D02*
X47540D01*
X48940Y204933D01*
Y204871D01*
G01X42281Y206333D02*
X46307D01*
G01X64000Y130125D02*
X60486D01*
X60411Y130200D01*
G01X64000Y133275D02*
X62600D01*
X62395Y133070D01*
X61123D01*
G01X64559Y141011D02*
Y136834D01*
X64000Y136275D01*
Y133275D01*
G01X79762Y366878D02*
X78206Y365322D01*
G01X75000Y406075D02*
X73976Y407099D01*
Y408665D01*
G01X97066Y384182D02*
X95510Y382626D01*
G01X108108Y392075D02*
Y395100D01*
G01X155000Y292575D02*
X153225D01*
X152400Y293400D01*
G01X152500Y289425D02*
X155000D01*
G01X160457Y142434D02*
X159000Y140977D01*
Y135000D01*
G01X179902Y164454D02*
X178346Y162898D01*
G01X176752Y155005D02*
Y154960D01*
X175359Y153567D01*
Y153286D01*
G01X179902Y173903D02*
X178346Y172347D01*
G01X179902Y186501D02*
X178346Y184945D01*
G01X179902Y211698D02*
X178346Y213254D01*
G01X179902Y199099D02*
X178346Y200655D01*
G01Y225852D02*
X179902Y224296D01*
G01X176752Y233745D02*
X175893Y234604D01*
X174079D01*
G01X177413Y249436D02*
X177113Y249136D01*
X174400D01*
G01X198799Y158155D02*
X197243Y156599D01*
G01X192500Y170753D02*
X194500Y172753D01*
X199948D01*
X201504Y171197D01*
X201949Y170753D01*
G01X198799Y180202D02*
X197243Y178646D01*
G01X189350Y183351D02*
X187794Y181795D01*
G01X198799Y170753D02*
X195650D01*
G01D02*
X194094Y169197D01*
G01X197243Y197506D02*
X198799Y195950D01*
G01Y189651D02*
Y189688D01*
X197243Y191244D01*
G01X189350Y195950D02*
X187794Y197506D01*
G01X189350Y189651D02*
X188839Y189140D01*
Y187012D01*
X189350Y186501D01*
G01X197243Y200655D02*
X198799Y199099D01*
G01X189350Y211698D02*
X187794Y213254D01*
G01X197243Y203805D02*
X198799Y202249D01*
G01X184645Y206955D02*
X186201Y205399D01*
G01D02*
X189350D01*
G01Y208548D02*
X189388D01*
X190944Y210104D01*
G01X189350Y202249D02*
Y202211D01*
X187794Y200655D01*
G01X189350Y199099D02*
X187794Y200655D01*
G01X186201Y208548D02*
X184645Y210104D01*
G01X190944Y213254D02*
X192500Y211698D01*
G01D02*
X193216Y210982D01*
Y209264D01*
X192500Y208548D01*
G01Y217997D02*
X190944Y219553D01*
G01X192500Y214847D02*
Y217997D01*
G01X198799D02*
X197243Y219553D01*
G01X195650Y217997D02*
X195687D01*
X197243Y219553D01*
G01X189350Y214847D02*
Y214810D01*
X187794Y213254D01*
G01X189350Y217997D02*
Y214847D01*
G01X195650Y227446D02*
X194094Y229002D01*
G01X198799Y224296D02*
X197243Y225852D01*
G01X195650Y230595D02*
X194094Y232151D01*
G01X186201Y230595D02*
X184645Y232151D01*
G01X198799Y233745D02*
X197243Y235301D01*
G01X198799Y227446D02*
X197243Y229002D01*
G01X198799Y230595D02*
X197243Y232151D01*
G01X211398Y158155D02*
X209842Y156599D01*
G01X208248Y180202D02*
X206692Y178646D01*
G01X211398Y183351D02*
X209842Y181795D01*
G01X208248Y170753D02*
X206692Y169197D01*
G01X205098Y170753D02*
X203542Y169197D01*
G01X201949Y180202D02*
X198799D01*
G01X211398D02*
Y180239D01*
X209842Y181795D01*
G01X205098Y180202D02*
X205136D01*
X206692Y178646D01*
G01X201949Y170753D02*
X200393Y169197D01*
G01X205098Y177052D02*
X203542Y175496D01*
G01X208248Y177052D02*
X206692Y175496D01*
G01X211398Y177052D02*
X209842Y175496D01*
G01X211398Y186501D02*
X209842Y184945D01*
G01Y197506D02*
X211398Y195950D01*
G01Y189651D02*
X208248D01*
G01Y192800D02*
X206692Y191244D01*
G01X208248Y199099D02*
X208249D01*
X209842Y197506D01*
G01X201949Y192800D02*
X201986D01*
X203542Y191244D01*
G01X201949Y195950D02*
X201986D01*
X203542Y197506D01*
G01D02*
X205098Y195950D01*
G01Y192800D02*
X203542Y191244D01*
G01X205098Y189651D02*
Y189688D01*
X203542Y191244D01*
G01X201949Y186501D02*
Y189651D01*
G01X198799Y186501D02*
Y189651D01*
G01X208248Y186501D02*
X208286D01*
X209842Y184945D01*
G01X205098Y186501D02*
X208248D01*
G01Y189651D02*
Y189688D01*
X206692Y191244D01*
G01X201949Y189651D02*
Y189688D01*
X200393Y191244D01*
G01X211398Y195950D02*
Y192800D01*
G01X205098Y195950D02*
X208248D01*
G01X198799D02*
Y192800D01*
G01X205098Y208548D02*
X203542Y210104D01*
G01X211398Y208548D02*
X209842Y210104D01*
G01X205098Y199099D02*
X203542Y200655D01*
G01X201949Y208548D02*
X200393Y210104D01*
G01X211398Y199099D02*
X209842Y200655D01*
G01X211398Y202249D02*
Y202211D01*
X209842Y200655D01*
G01X208248Y202249D02*
X205098D01*
G01X208248Y208548D02*
X208286D01*
X209842Y210104D01*
G01X198799Y199099D02*
X201949D01*
G01X205098Y202249D02*
Y202211D01*
X203542Y200655D01*
G01X198799Y202249D02*
X201949D01*
G01X205098Y211698D02*
X208248D01*
G01X198799D02*
X198837D01*
X200393Y213254D01*
G01X201949Y211698D02*
X200393Y213254D01*
G01X203542D02*
X205098Y211698D01*
G01X211398D02*
X209842Y213254D01*
G01X201949Y217997D02*
X200393Y219553D01*
G01X205098Y221147D02*
X203542Y222703D01*
G01X201949Y221147D02*
X200393Y222703D01*
G01X201949Y224296D02*
X200393Y225852D01*
G01X205098Y230595D02*
X203542Y232151D01*
G01X205098Y233745D02*
X203542Y235301D01*
G01X223996Y158155D02*
X225552Y156599D01*
G01X223996Y180202D02*
X225552Y178646D01*
G01X214547Y170753D02*
X212991Y169197D01*
G01X217697Y174852D02*
Y177052D01*
G01X220846Y170753D02*
X222402Y169197D01*
G01X214547Y183351D02*
X212991Y181795D01*
G01X214547Y180202D02*
Y180239D01*
X212991Y181795D01*
G01X223996Y177052D02*
Y177090D01*
X225552Y178646D01*
G01X227146Y170753D02*
X228702Y169197D01*
G01X227146Y177052D02*
Y170753D01*
G01X217697Y180202D02*
X219253Y178646D01*
G01X217697Y183351D02*
Y180202D01*
G01X227146D02*
X228702Y178646D01*
G01X223996Y183351D02*
X225552Y181795D01*
G01X214547Y177052D02*
Y174852D01*
G01X220846Y189651D02*
X219290Y191207D01*
G01X227146Y192800D02*
X228702Y191244D01*
G01X227146Y189651D02*
Y189688D01*
X228702Y191244D01*
G01X223996Y186501D02*
X225552Y184945D01*
G01X220846Y186501D02*
X223996D01*
G01X230295Y195950D02*
X227146D01*
G01X223996Y199099D02*
X225552Y197543D01*
G01X220846Y192800D02*
X222402Y191244D01*
G01X217697Y189651D02*
X219253Y188095D01*
G01X217697Y186501D02*
Y186539D01*
X219253Y188095D01*
G01X227146Y183351D02*
X228702Y181795D01*
G01X220846Y183351D02*
X223996D01*
G01X222402Y213254D02*
X220846Y211698D01*
G01Y205399D02*
X222402Y206955D01*
G01X214547Y205399D02*
X212991Y206955D01*
G01X214547Y208548D02*
X212991Y210104D01*
G01X223996Y208548D02*
X223995D01*
X222402Y206955D01*
G01X223996Y205399D02*
X223958D01*
X222402Y206955D01*
G01X223996Y211698D02*
X223958D01*
X222402Y213254D01*
G01X223996Y202249D02*
Y199099D01*
G01X220846Y202249D02*
X223996D01*
G01X220846Y211698D02*
X221310Y211234D01*
Y209012D01*
X220846Y208548D01*
G01X227146Y199099D02*
X228702Y200655D01*
G01X227146Y202249D02*
X228702Y203805D01*
G01X217697Y208548D02*
X219253Y210104D01*
G01X217697Y211698D02*
X219253Y213254D01*
G01X217697Y205399D02*
X219253Y206955D01*
G01X217697Y202249D02*
X219253Y203805D01*
G01X217697Y199099D02*
X219253Y200655D01*
G01X228702Y210104D02*
X227146Y208548D01*
G01Y217997D02*
X228702Y219553D01*
G01X214547Y217997D02*
X212991Y219553D01*
G01X217697Y230595D02*
X219253Y232151D01*
G01X233445Y167603D02*
X235001Y166047D01*
G01X236594Y167603D02*
X238150Y166047D01*
G01X230295Y167603D02*
X231851Y166047D01*
G01X235001Y169197D02*
X235002Y169196D01*
X236594Y167603D01*
G01X231851Y169197D02*
G02X231824Y169132I-92J0D01*
G01X230295Y167603D01*
G01Y177052D02*
Y173903D01*
X233445Y170753D01*
G01X238150Y169197D02*
G03X238215Y169224I0J92D01*
G01X239744Y170753D01*
G01X230295Y180202D02*
X231851Y178646D01*
G01X230295Y170753D02*
X231851Y169197D01*
G01X236594Y170753D02*
G03X236531Y170727I0J-89D01*
G01X235001Y169197D01*
G01X233445Y180202D02*
X235001Y178646D01*
G01X233445Y177052D02*
X235001Y175496D01*
G01X239744Y192800D02*
X241300Y191244D01*
G01X230295Y192800D02*
X231851Y191244D01*
G01X233445Y186501D02*
X235001Y184945D01*
G01X230295Y189651D02*
Y189688D01*
X231851Y191244D01*
G01X233445Y183351D02*
Y183389D01*
X235001Y184945D01*
G01X230295Y183351D02*
X233445D01*
G01Y199099D02*
X230296Y195950D01*
X230295D01*
G01X235001Y200655D02*
X233445Y199099D01*
G01X239744Y211698D02*
X241300Y213254D01*
G01X228739D02*
X230295Y211698D01*
G01X233445Y205399D02*
X235001Y206955D01*
G01X230295Y205399D02*
X230786Y205890D01*
X232954D01*
X233445Y205399D01*
G01X230295Y211698D02*
X230733Y212136D01*
X233007D01*
X233445Y211698D01*
G01X230295Y199099D02*
X230258D01*
X228702Y200655D01*
G01X233445Y202249D02*
X235001Y203805D01*
G01X230295Y202249D02*
X231851Y203805D01*
G01X239744Y205399D02*
Y208548D01*
G01D02*
X241300Y210104D01*
G01X233445Y208548D02*
X235001Y210104D01*
G01X233445Y217997D02*
X235001Y219553D01*
G01X239744Y224296D02*
X238188Y225852D01*
G01X236594Y217997D02*
X238150Y219553D01*
G01X239744Y214847D02*
Y214810D01*
X241300Y213254D01*
G01X239744Y217997D02*
X239706D01*
X238150Y219553D01*
G01X239744Y230595D02*
X241300Y232151D01*
G01X230295Y230595D02*
X231851Y232151D01*
G01X228200Y459100D02*
X228602Y459502D01*
Y465590D01*
G01X249193Y161304D02*
X250749Y159748D01*
G01X242894Y155005D02*
Y155043D01*
X244450Y156599D01*
G01X242894Y158155D02*
Y158192D01*
X244450Y159748D01*
G01X242894Y158155D02*
X244450Y156599D01*
G01X255492Y155005D02*
Y152905D01*
G01X252342Y173903D02*
X253898Y172347D01*
G01X252342Y180202D02*
X253898Y178646D01*
G01X246043Y183351D02*
X247599Y181795D01*
G01X246043Y177052D02*
X247599Y175496D01*
G01X252342Y186501D02*
X253898Y184945D01*
G01X252342Y192800D02*
X253898Y191244D01*
G01X246043Y195950D02*
X247599Y197506D01*
G01X246043Y189651D02*
X247599Y188095D01*
G01X246043Y202249D02*
X247599Y203805D01*
G01X252342Y205399D02*
X253898Y206955D01*
G01X252342Y199099D02*
X253898Y200655D01*
G01X242894Y211698D02*
X243451Y211141D01*
Y209151D01*
X242894Y208594D01*
Y208548D01*
G01Y202249D02*
X244450Y203805D01*
G01X242894Y205399D02*
X244450Y203843D01*
Y203805D01*
G01X255492Y217997D02*
X257048Y219553D01*
G01X255492Y227446D02*
X257048Y225890D01*
G01X252342Y224296D02*
X255492Y227446D01*
G01X249193Y217997D02*
X250749Y219553D01*
G01X246043Y227446D02*
X244487Y229002D01*
G01X249193Y230595D02*
X250749Y232151D01*
G01X255492Y233745D02*
X257048Y235301D01*
G01X244020Y235518D02*
X244038Y235500D01*
X244100D01*
X245855Y233745D01*
X246043D01*
G01X291380Y106255D02*
X287177D01*
X284222Y103300D01*
G01D02*
X286022Y101500D01*
X287825D01*
X288925Y100400D01*
G01X287608Y164990D02*
X285980Y163487D01*
G01X287608Y174439D02*
X286105Y172936D01*
G01Y182385D02*
X287608Y183888D01*
G01Y177588D02*
X286105Y176085D01*
G01X287608Y168140D02*
X285482Y168102D01*
G01X287608Y190187D02*
X285482D01*
G01X287608Y196486D02*
X286105Y197989D01*
G01X287608Y187037D02*
X286105Y185534D01*
G01X287608Y193336D02*
X286105Y194839D01*
G01X287608Y199636D02*
X286105Y201139D01*
G01Y204288D02*
X287608Y205935D01*
G01Y202785D02*
X286105Y204288D01*
G01X287608Y212234D02*
X286105Y213721D01*
G01X287608Y180738D02*
X289111Y179235D01*
G01X290757Y187037D02*
X289254Y185534D01*
G01X290757Y196486D02*
X289254Y197989D01*
G01X290757Y202785D02*
X289091Y204331D01*
G01X290757Y212234D02*
X289254Y213737D01*
G01X290757Y209084D02*
X289254Y210587D01*
G01X293907Y199636D02*
X292361Y197970D01*
G01X293907Y209084D02*
X295410Y210587D01*
G01X316025Y62700D02*
X314350Y64375D01*
Y66950D01*
X315341Y67941D01*
X317580D01*
G01X316025Y62700D02*
Y60200D01*
G01X305936Y138297D02*
X305436D01*
X304436Y137297D01*
Y135897D01*
G01X309936Y138297D02*
X305936D01*
G01X313936D02*
X309936D01*
G01X306505Y164990D02*
X308008Y163487D01*
G01X312804Y164990D02*
X314307Y163487D01*
G01X311301Y182385D02*
X312804Y183888D01*
G01Y180738D02*
X314930D01*
G01X312804Y168140D02*
X314930D01*
G01X309655Y193336D02*
X311158Y194839D01*
G01X312804Y190187D02*
X314307Y191690D01*
G01X312804Y187037D02*
X314307Y185534D01*
G01X309655Y187037D02*
X311158Y188540D01*
G01X306505Y193336D02*
X308008Y194839D01*
G01X309655Y196486D02*
X311158Y197989D01*
G01X309655Y202785D02*
X311158Y204288D01*
G01X309655Y212234D02*
X311158Y213737D01*
G01X312804Y205935D02*
X314307Y207438D01*
G01X309655Y199636D02*
X311158Y201139D01*
G01X312804Y202785D02*
X314307Y204288D01*
G01X312804Y209084D02*
X314307Y210587D01*
G01X312804Y212234D02*
X314307Y213737D01*
G01X305306Y273256D02*
X304806Y273756D01*
X304428D01*
X302687Y275497D01*
G01X308500Y382100D02*
X307723Y381323D01*
X303512D01*
G01X319175Y62700D02*
Y60200D01*
G01X325020Y73059D02*
X324000D01*
X322600Y74459D01*
Y76100D01*
G01X337400Y154911D02*
X339800D01*
G01X337400Y159911D02*
X339800D01*
G01X337400Y164911D02*
X338800D01*
X339800Y165911D01*
G01X337400Y169911D02*
X339800D01*
G01X337400Y179911D02*
X339800D01*
G01X337400Y174911D02*
X337800D01*
X339800Y176911D01*
G01X337400Y189911D02*
X339800D01*
G54D112*
X236220Y424016D03*
X301181D03*
G54D103*
X163334Y90590D03*
Y83898D03*
X159988D03*
Y90590D03*
X172758D03*
Y83898D03*
X169412D03*
Y90590D03*
G54D10*
X-56709Y43008D03*
X-61709Y56192D03*
X-51709D03*
X-61100Y250316D03*
X-56100Y263500D03*
X-61000Y382816D03*
X-56000Y396000D03*
X-51100Y250316D03*
X-51000Y382816D03*
X-30000Y43000D03*
X-35000Y56184D03*
X-25000D03*
X-25100Y250316D03*
X-35100D03*
X-30100Y263500D03*
X-36000Y418816D03*
X-26000D03*
X-31000Y432000D03*
G54D121*
X372604Y-455313D03*
Y-430313D03*
X372664Y-223791D03*
Y-198791D03*
X372576Y-177041D03*
Y-152041D03*
X372664Y4481D03*
Y29481D03*
X372604Y51231D03*
Y76231D03*
X372664Y373753D03*
Y398753D03*
X393692Y-481375D03*
X382604Y-455313D03*
X393692Y-456375D03*
X382604Y-430313D03*
X382664Y-223791D03*
Y-198791D03*
X382576Y-177041D03*
Y-152041D03*
X393780Y-128853D03*
Y-103853D03*
X393750Y-82222D03*
Y-57222D03*
X382664Y4481D03*
Y29481D03*
X382604Y51231D03*
Y76231D03*
X393750Y200538D03*
Y225538D03*
Y247050D03*
Y272050D03*
X382664Y373753D03*
X393750Y398810D03*
X382664Y398753D03*
X393750Y423810D03*
X403692Y-481375D03*
Y-456375D03*
X403780Y-128853D03*
Y-103853D03*
X403750Y-82222D03*
D03*
Y-57222D03*
D03*
Y200538D03*
D03*
Y225538D03*
D03*
Y247050D03*
D03*
Y272050D03*
D03*
Y398810D03*
D03*
Y423810D03*
D03*
X413750Y-82222D03*
Y-57222D03*
Y200538D03*
Y225538D03*
Y247050D03*
Y272050D03*
Y398810D03*
Y423810D03*
G54D140*
G01X52500Y432075D02*
X53775Y433350D01*
Y436727D01*
X64520Y447473D01*
X66381Y451964D01*
Y462260D01*
X65925Y462716D01*
Y465590D01*
G01X56500Y432075D02*
X55225Y433350D01*
Y436126D01*
X65750Y446651D01*
X67831Y451675D01*
Y462278D01*
X68287Y462734D01*
Y465590D01*
G01X56250Y424200D02*
X55225Y425225D01*
Y427650D01*
X56500Y428925D01*
G01X52750Y424200D02*
X53775Y425225D01*
Y427650D01*
X52500Y428925D01*
G01X80098Y465590D02*
Y462703D01*
X80555Y462246D01*
Y458320D01*
X75600Y446358D01*
Y435350D01*
X73175Y432925D01*
Y425224D01*
X72150Y424199D01*
G01X82461Y465590D02*
Y462822D01*
X82005Y462366D01*
Y458031D01*
X77050Y446069D01*
Y434749D01*
X74625Y432324D01*
Y425224D01*
X75650Y424199D01*
G01X87185Y465590D02*
Y462716D01*
X87641Y462260D01*
Y457441D01*
X84307Y454107D01*
X83000Y450952D01*
Y449095D01*
X81990Y448085D01*
G01X89547Y465590D02*
Y462734D01*
X89091Y462278D01*
Y456840D01*
X85537Y453285D01*
X84450Y450663D01*
Y449125D01*
X85490Y448085D01*
G01X92801Y452793D02*
X93800Y453792D01*
Y456860D01*
X94728Y459101D01*
Y462272D01*
X94272Y462728D01*
Y465590D01*
G01X102190Y66725D02*
X103215Y65700D01*
X106401D01*
X107349Y66648D01*
X107969D01*
G01X102190Y63225D02*
X103215Y64250D01*
X106449D01*
X107397Y63302D01*
X107969D01*
G01X95870Y445483D02*
X96923Y446536D01*
Y447423D01*
X101815Y452315D01*
Y462286D01*
X101358Y462743D01*
Y465590D01*
G01X103721D02*
Y462722D01*
X103265Y462266D01*
Y451714D01*
X98373Y446822D01*
Y446480D01*
X99370Y445483D01*
G01X96301Y452793D02*
X95250Y453844D01*
Y456571D01*
X96178Y458812D01*
Y462278D01*
X96634Y462734D01*
Y465590D01*
G01X112876Y62963D02*
X114322D01*
X114661Y63302D01*
G01X109726Y62963D02*
X108308D01*
X107969Y63302D01*
G01X114661Y66648D02*
X115353D01*
X116302Y65699D01*
X125363D01*
X128575Y68911D01*
G01X112876Y66963D02*
X114346D01*
X114661Y66648D01*
G01Y63302D02*
X115337D01*
X116284Y64249D01*
X125363D01*
X128575Y61037D01*
G01X109726Y66963D02*
X108284D01*
X107969Y66648D01*
G01X128575Y61037D02*
X131787Y64249D01*
X136658D01*
X141168Y62380D01*
X146869Y56679D01*
Y54271D01*
X152698Y45550D01*
X154191Y44058D01*
X167309D01*
X169710Y46459D01*
Y52117D01*
X170270Y52677D01*
X172922D01*
G01X128575Y68911D02*
X131787Y65699D01*
X136947D01*
X139468Y64654D01*
X139469D01*
X141990Y63610D01*
X148319Y57281D01*
Y54712D01*
X149520Y52914D01*
X150742Y52672D01*
X151676Y51274D01*
X151433Y50053D01*
X153825Y46475D01*
X154792Y45508D01*
X155672D01*
X156664Y46500D01*
X158120D01*
X159112Y45508D01*
X160792D01*
X161824Y46540D01*
X163200D01*
X164232Y45508D01*
X166708D01*
X168260Y47060D01*
Y52117D01*
X167700Y52677D01*
X165048D01*
G01X161111Y58583D02*
X158459D01*
X157899Y59143D01*
Y61399D01*
X160550Y64050D01*
X162451D01*
X164492Y66091D01*
Y68772D01*
X164751Y69031D01*
Y70074D01*
G01X153237Y58583D02*
X155889D01*
X156449Y59143D01*
Y62000D01*
X159949Y65500D01*
X161850D01*
X163042Y66692D01*
Y68776D01*
X162782Y69036D01*
Y70074D01*
G01X164751D02*
Y73126D01*
G01D02*
Y74169D01*
X164492Y74428D01*
Y77378D01*
X162386Y79484D01*
Y81866D01*
X163334Y82814D01*
Y83898D01*
G01X162782Y70074D02*
Y73126D01*
G01D02*
Y74164D01*
X163042Y74424D01*
Y76777D01*
X160936Y78883D01*
Y81782D01*
X159988Y82730D01*
Y83898D01*
G01X163673Y88805D02*
X163334Y89144D01*
Y90590D01*
G01X163423Y96281D02*
X162323Y95181D01*
Y92871D01*
X163334Y91860D01*
Y90590D01*
G01X159673Y88805D02*
X159988Y89120D01*
Y90590D01*
G01X159923Y96281D02*
X160873Y95331D01*
Y92796D01*
X159988Y91911D01*
Y90590D01*
G01X184733Y58583D02*
X182081D01*
X181521Y59143D01*
Y61879D01*
X179050Y64350D01*
X172420D01*
X170397Y66373D01*
Y68778D01*
X170656Y69037D01*
Y70074D01*
G01X176859Y58583D02*
X179511D01*
X180071Y59143D01*
Y61278D01*
X178449Y62900D01*
X171819D01*
X168947Y65772D01*
Y68772D01*
X168687Y69032D01*
Y70074D01*
G01X170656D02*
Y73126D01*
G01D02*
Y74163D01*
X170397Y74422D01*
Y77527D01*
X171810Y78940D01*
Y81790D01*
X172758Y82738D01*
Y83898D01*
G01X168687Y70074D02*
Y73126D01*
G01D02*
Y74168D01*
X168947Y74428D01*
Y78128D01*
X170360Y79541D01*
Y81758D01*
X169412Y82706D01*
Y83898D01*
G01X173097Y88805D02*
X172758Y89144D01*
Y90590D01*
G01X172847Y96281D02*
X171767Y95201D01*
Y92851D01*
X172758Y91860D01*
Y90590D01*
G01X169097Y88805D02*
X169412Y89120D01*
Y90590D01*
G01D02*
Y91811D01*
X170317Y92716D01*
Y95311D01*
X169347Y96281D01*
G01X246205Y138862D02*
X246983D01*
X247865Y139744D01*
Y140663D01*
X246853Y143108D01*
X245807Y143541D01*
X245233Y144927D01*
X245666Y145973D01*
X245092Y147358D01*
X243269Y149181D01*
X242137D01*
X241005Y150313D01*
Y151444D01*
X240288Y152161D01*
Y152162D01*
X239874Y152576D01*
Y154875D01*
X239744Y155005D01*
G01X250212Y138862D02*
X249315Y139759D01*
Y140952D01*
X246322Y148180D01*
X241314Y153187D01*
G01X255175Y110300D02*
X256300Y109175D01*
Y107186D01*
X255213Y106099D01*
G01X249988Y105792D02*
X248963Y106817D01*
Y110140D01*
X251150Y115420D01*
Y121224D01*
X248934Y132365D01*
Y134434D01*
X250212Y135712D01*
G01X246488Y105792D02*
X247513Y106817D01*
Y110429D01*
X249700Y115709D01*
Y121081D01*
X247484Y132222D01*
Y134433D01*
X246205Y135712D01*
G01X254332Y117233D02*
X255611Y118512D01*
Y123581D01*
X254761Y124431D01*
Y126111D01*
X255611Y126961D01*
Y128641D01*
X254761Y129491D01*
Y131171D01*
X255611Y132021D01*
Y135620D01*
X254841Y136390D01*
Y138010D01*
X255611Y138780D01*
Y143289D01*
X255151Y143749D01*
X254018D01*
X252958Y144810D01*
Y145942D01*
X251898Y147002D01*
X250765D01*
X249705Y148063D01*
Y149195D01*
X247225Y151675D01*
G01X255175Y110300D02*
X255795Y110920D01*
Y113488D01*
X255200Y114083D01*
X254332D01*
G01X247613Y153338D02*
X257061Y143890D01*
Y118511D01*
X258339Y117233D01*
G01X249193Y233745D02*
X250749Y235301D01*
G01X258925Y110300D02*
X257750Y109125D01*
Y107062D01*
X258713Y106099D01*
G01X258339Y114083D02*
X257245Y112989D01*
Y111980D01*
X258925Y110300D01*
G01X397766Y261650D02*
Y262270D01*
X398025Y262529D01*
Y279108D01*
X400037Y281980D01*
X414223Y284484D01*
X415131Y285779D01*
X414482Y289455D01*
X413186Y290364D01*
X388895Y286079D01*
X386613Y287676D01*
X385755Y292538D01*
X387353Y294817D01*
X414302Y299571D01*
X415210Y300867D01*
X414561Y304543D01*
X413265Y305451D01*
X388936Y301160D01*
X386654Y302757D01*
X385796Y307619D01*
X387393Y309898D01*
X414257Y314637D01*
X415165Y315933D01*
X414516Y319609D01*
X413220Y320517D01*
X388715Y316195D01*
X386433Y317792D01*
X385575Y322655D01*
X387173Y324933D01*
X413205Y329525D01*
X414113Y330820D01*
X413464Y334496D01*
X412167Y335404D01*
X388341Y331202D01*
X386059Y332800D01*
X385201Y337661D01*
X386799Y339941D01*
X410225Y344073D01*
X411133Y345369D01*
X410484Y349045D01*
X409188Y349953D01*
X388038Y346222D01*
X385755Y347820D01*
X384897Y352681D01*
X386495Y354960D01*
X410503Y359196D01*
X411411Y360492D01*
X410762Y364168D01*
X409466Y365076D01*
X387393Y361182D01*
X385111Y362780D01*
X384253Y367641D01*
X385851Y369920D01*
X410650Y374295D01*
X411558Y375592D01*
X410909Y379268D01*
X409614Y380176D01*
X393112Y377265D01*
X390830Y378863D01*
X389972Y383724D01*
X391570Y386004D01*
X398137Y387162D01*
X399045Y388458D01*
X398025Y394239D01*
Y408331D01*
X397766Y408590D01*
Y409210D01*
G01X399734Y261650D02*
Y262270D01*
X399475Y262529D01*
Y278650D01*
X400880Y280656D01*
X415066Y283160D01*
X416664Y285439D01*
X415806Y290298D01*
X413527Y291897D01*
X389235Y287612D01*
X387937Y288520D01*
X387288Y292198D01*
X388196Y293493D01*
X415145Y298247D01*
X416743Y300527D01*
X415885Y305386D01*
X413605Y306984D01*
X389276Y302693D01*
X387978Y303601D01*
X387329Y307279D01*
X388236Y308574D01*
X415100Y313313D01*
X416698Y315593D01*
X415840Y320452D01*
X413560Y322050D01*
X389055Y317728D01*
X387757Y318636D01*
X387108Y322314D01*
X388016Y323609D01*
X414048Y328201D01*
X415646Y330480D01*
X414788Y335339D01*
X412507Y336937D01*
X388681Y332735D01*
X387383Y333644D01*
X386734Y337321D01*
X387642Y338617D01*
X411068Y342749D01*
X412666Y345029D01*
X411808Y349888D01*
X409528Y351486D01*
X388378Y347755D01*
X387079Y348664D01*
X386430Y352341D01*
X387338Y353636D01*
X411346Y357872D01*
X412944Y360152D01*
X412086Y365011D01*
X409806Y366609D01*
X387733Y362715D01*
X386435Y363624D01*
X385786Y367301D01*
X386694Y368596D01*
X411494Y372971D01*
X413091Y375252D01*
X412233Y380111D01*
X409954Y381709D01*
X393452Y378798D01*
X392154Y379707D01*
X391505Y383384D01*
X392413Y384680D01*
X398980Y385838D01*
X400578Y388118D01*
X399475Y394366D01*
Y408331D01*
X399734Y408590D01*
Y409210D01*
G01X407766Y-67622D02*
Y-67002D01*
X408025Y-66743D01*
Y-51507D01*
X410474Y-49058D01*
X416524Y-47991D01*
X417432Y-46695D01*
X416783Y-43020D01*
X415486Y-42111D01*
X401965Y-44495D01*
X399683Y-42898D01*
X398825Y-38036D01*
X400422Y-35757D01*
X416370Y-32945D01*
X417278Y-31649D01*
X416629Y-27974D01*
X415332Y-27065D01*
X401822Y-29447D01*
X399541Y-27850D01*
X398683Y-22988D01*
X400281Y-20709D01*
X416591Y-17833D01*
X417499Y-16536D01*
X416850Y-12861D01*
X415553Y-11952D01*
X401926Y-14355D01*
X399645Y-12758D01*
X398787Y-7896D01*
X400385Y-5616D01*
X416444Y-2785D01*
X417352Y-1489D01*
X416703Y2186D01*
X415406Y3095D01*
X401902Y714D01*
X399621Y2311D01*
X398763Y7173D01*
X400361Y9453D01*
X416487Y12296D01*
X417395Y13593D01*
X416746Y17268D01*
X415449Y18177D01*
X401912Y15790D01*
X399631Y17387D01*
X398773Y22249D01*
X400370Y24528D01*
X416480Y27368D01*
X417388Y28664D01*
X416739Y32339D01*
X415442Y33248D01*
X397723Y30124D01*
X395442Y31721D01*
X394584Y36583D01*
X396182Y38863D01*
X421026Y43244D01*
X421934Y44540D01*
X421285Y48215D01*
X419988Y49124D01*
X397106Y45089D01*
X394825Y46686D01*
X393967Y51548D01*
X395565Y53828D01*
X421152Y58340D01*
X422060Y59636D01*
X421411Y63311D01*
X420114Y64220D01*
X396955Y60136D01*
X394674Y61733D01*
X393816Y66595D01*
X395414Y68875D01*
X421429Y73462D01*
X422337Y74758D01*
X421688Y78433D01*
X420391Y79342D01*
X397103Y75236D01*
X394822Y76833D01*
X393964Y81695D01*
X395562Y83975D01*
X421221Y88499D01*
X422129Y89795D01*
X421480Y93470D01*
X420183Y94379D01*
X396940Y90281D01*
X394659Y91878D01*
X393801Y96740D01*
X395399Y99020D01*
X421308Y103588D01*
X422216Y104884D01*
X421567Y108559D01*
X420270Y109468D01*
X396687Y105310D01*
X394406Y106907D01*
X393548Y111769D01*
X395145Y114048D01*
X421054Y118616D01*
X421962Y119912D01*
X421313Y123587D01*
X420016Y124496D01*
X397131Y120461D01*
X394850Y122058D01*
X393992Y126920D01*
X395590Y129201D01*
X421301Y133731D01*
X422209Y135029D01*
X421560Y138705D01*
X420263Y139614D01*
X397265Y135559D01*
X394984Y137156D01*
X394126Y142019D01*
X395724Y144297D01*
X420937Y148743D01*
X421845Y150039D01*
X421196Y153714D01*
X419899Y154623D01*
X396799Y150550D01*
X394518Y152148D01*
X393660Y157010D01*
X395258Y159288D01*
X421192Y163861D01*
X422100Y165157D01*
X421451Y168832D01*
X420154Y169741D01*
X396980Y165655D01*
X394699Y167253D01*
X393841Y172114D01*
X395439Y174394D01*
X421070Y178913D01*
X421978Y180209D01*
X421329Y183884D01*
X420032Y184793D01*
X397129Y180755D01*
X394848Y182352D01*
X393990Y187214D01*
X395588Y189494D01*
X407737Y191636D01*
X408645Y192932D01*
X408025Y196442D01*
Y210059D01*
X407766Y210318D01*
Y210938D01*
G01X409734Y-67622D02*
Y-67002D01*
X409475Y-66743D01*
Y-52108D01*
X411176Y-50407D01*
X417367Y-49315D01*
X418965Y-47035D01*
X418107Y-42177D01*
X415826Y-40578D01*
X402305Y-42962D01*
X401007Y-42054D01*
X400358Y-38376D01*
X401265Y-37081D01*
X417213Y-34269D01*
X418811Y-31989D01*
X417953Y-27131D01*
X415672Y-25532D01*
X402162Y-27914D01*
X400865Y-27006D01*
X400216Y-23328D01*
X401124Y-22033D01*
X417435Y-19158D01*
X419032Y-16876D01*
X418174Y-12018D01*
X415893Y-10419D01*
X402266Y-12822D01*
X400969Y-11914D01*
X400320Y-8236D01*
X401228Y-6940D01*
X417287Y-4109D01*
X418885Y-1829D01*
X418027Y3029D01*
X415746Y4628D01*
X402242Y2247D01*
X400945Y3155D01*
X400296Y6833D01*
X401204Y8129D01*
X417331Y10971D01*
X418928Y13253D01*
X418070Y18111D01*
X415789Y19710D01*
X402252Y17323D01*
X400955Y18231D01*
X400306Y21909D01*
X401213Y23204D01*
X417323Y26044D01*
X418921Y28324D01*
X418063Y33182D01*
X415782Y34781D01*
X398063Y31657D01*
X396766Y32565D01*
X396117Y36243D01*
X397025Y37539D01*
X421869Y41920D01*
X423467Y44200D01*
X422609Y49058D01*
X420328Y50657D01*
X397446Y46622D01*
X396149Y47530D01*
X395500Y51208D01*
X396408Y52504D01*
X421995Y57016D01*
X423593Y59296D01*
X422735Y64154D01*
X420454Y65753D01*
X397295Y61669D01*
X395998Y62577D01*
X395349Y66255D01*
X396257Y67551D01*
X422272Y72138D01*
X423870Y74418D01*
X423012Y79276D01*
X420731Y80875D01*
X397443Y76769D01*
X396146Y77677D01*
X395497Y81355D01*
X396405Y82651D01*
X422064Y87175D01*
X423662Y89455D01*
X422804Y94313D01*
X420523Y95912D01*
X397280Y91814D01*
X395983Y92722D01*
X395334Y96400D01*
X396242Y97696D01*
X422151Y102264D01*
X423749Y104544D01*
X422891Y109402D01*
X420610Y111001D01*
X397027Y106843D01*
X395730Y107751D01*
X395081Y111429D01*
X395988Y112724D01*
X421897Y117292D01*
X423495Y119572D01*
X422637Y124430D01*
X420356Y126029D01*
X397471Y121994D01*
X396174Y122902D01*
X395525Y126580D01*
X396433Y127877D01*
X422145Y132407D01*
X423742Y134690D01*
X422884Y139548D01*
X420603Y141147D01*
X397605Y137092D01*
X396308Y138000D01*
X395659Y141678D01*
X396567Y142973D01*
X421780Y147419D01*
X423378Y149699D01*
X422520Y154557D01*
X420239Y156156D01*
X397139Y152083D01*
X395842Y152991D01*
X395193Y156669D01*
X396101Y157964D01*
X422035Y162537D01*
X423633Y164817D01*
X422775Y169675D01*
X420494Y171274D01*
X397320Y167188D01*
X396023Y168096D01*
X395374Y171774D01*
X396282Y173070D01*
X421913Y177589D01*
X423511Y179869D01*
X422653Y184727D01*
X420372Y186326D01*
X397469Y182288D01*
X396172Y183196D01*
X395523Y186874D01*
X396431Y188170D01*
X408580Y190312D01*
X410178Y192592D01*
X409475Y196570D01*
Y210059D01*
X409734Y210318D01*
Y210938D01*
G01X451000Y420000D02*
X447285D01*
X446725Y419440D01*
Y411854D01*
X444756Y409885D01*
X421400D01*
X420280Y408765D01*
Y405945D01*
X421400Y404825D01*
X470831D01*
X472800Y402856D01*
Y398834D01*
X470831Y396865D01*
X421400D01*
X420280Y395745D01*
Y392925D01*
X421400Y391805D01*
X471201D01*
X473170Y389836D01*
Y385814D01*
X471201Y383845D01*
X421400D01*
X420280Y382725D01*
Y379905D01*
X421400Y378785D01*
X471201D01*
X473170Y376816D01*
Y372794D01*
X471201Y370825D01*
X421400D01*
X420280Y369705D01*
Y366885D01*
X421400Y365765D01*
X471201D01*
X473170Y363796D01*
Y359774D01*
X471201Y357805D01*
X421400D01*
X420280Y356685D01*
Y353865D01*
X421400Y352745D01*
X471201D01*
X473170Y350776D01*
Y346754D01*
X471201Y344785D01*
X447845D01*
X446725Y343665D01*
Y336560D01*
X447285Y336000D01*
X451000D01*
G01X441000Y420000D02*
X444715D01*
X445275Y419440D01*
Y412455D01*
X444155Y411335D01*
X420799D01*
X418830Y409366D01*
Y405344D01*
X420799Y403375D01*
X470230D01*
X471350Y402255D01*
Y399435D01*
X470230Y398315D01*
X420799D01*
X418830Y396346D01*
Y392324D01*
X420799Y390355D01*
X470600D01*
X471720Y389235D01*
Y386415D01*
X470600Y385295D01*
X420799D01*
X418830Y383326D01*
Y379304D01*
X420799Y377335D01*
X470600D01*
X471720Y376215D01*
Y373395D01*
X470600Y372275D01*
X420799D01*
X418830Y370306D01*
Y366284D01*
X420799Y364315D01*
X470600D01*
X471720Y363195D01*
Y360375D01*
X470600Y359255D01*
X420799D01*
X418830Y357286D01*
Y353264D01*
X420799Y351295D01*
X470600D01*
X471720Y350175D01*
Y347355D01*
X470600Y346235D01*
X447244D01*
X445275Y344266D01*
Y336560D01*
X444715Y336000D01*
X441000D01*
G54D131*
G01X22638Y27520D02*
X25645D01*
X27323Y25842D01*
G01X31920Y186610D02*
X33005Y185525D01*
Y184247D01*
G01X21000Y316925D02*
X25100D01*
X25125Y316900D01*
G01X28275D02*
X29675Y315500D01*
X30700D01*
G01X32000Y326300D02*
X30700Y325000D01*
X28260D01*
G01X23535Y329990D02*
X20179Y328600D01*
X19975D01*
G01X25125Y316900D02*
Y318714D01*
X25811Y319400D01*
G01X28275Y316900D02*
Y317376D01*
X32400Y321501D01*
Y323000D01*
X34400Y325000D01*
X35740D01*
G01X35044Y35751D02*
X36925Y37632D01*
Y38000D01*
G01X48038Y45897D02*
Y44647D01*
X50425Y42260D01*
Y38716D01*
X50641Y38500D01*
G01X43926Y62248D02*
X42755D01*
X41941Y63062D01*
Y64760D01*
G01X50508Y57459D02*
X48170D01*
X47312Y58317D01*
X45161D01*
G01X52500Y69925D02*
X49374D01*
X47059Y72240D01*
G01X45276Y98488D02*
X45957D01*
X46469Y99000D01*
X56102D01*
G01X45461Y191535D02*
Y192221D01*
X43780Y193902D01*
Y194324D01*
X42392Y195712D01*
G01X47294Y187525D02*
Y188005D01*
X45461Y189838D01*
Y191535D01*
G01X45559Y210701D02*
X46684Y211826D01*
X47313D01*
X47714Y212227D01*
G01X45559Y214718D02*
X45752Y214911D01*
X47973D01*
X48059Y214825D01*
G01X40500Y234075D02*
Y236900D01*
G01X43525Y241000D02*
X42525Y242000D01*
X40700D01*
X39567Y243133D01*
G01Y246116D02*
Y243133D01*
G01X48440Y255685D02*
X52440D01*
G01X46925Y332000D02*
X44200D01*
G01X44500Y355500D02*
X43500Y354500D01*
X43000D01*
X41075Y352575D01*
Y352000D01*
G01X40500Y367075D02*
X39700D01*
X38200Y365575D01*
Y364855D01*
G01X44525Y387800D02*
X44625Y387700D01*
X46925D01*
G01X37675Y415700D02*
Y411900D01*
G01D02*
X37350Y411575D01*
Y410475D01*
X36600Y409725D01*
Y408600D01*
G01X53000Y41500D02*
X50641Y39141D01*
Y38500D01*
G01X57500Y75500D02*
Y73000D01*
X54425Y69925D01*
X52500D01*
G01X60000Y75500D02*
Y71657D01*
X54418Y66075D01*
X52500D01*
G01X63400Y116450D02*
X62570D01*
X60112Y113992D01*
G01X60400Y186825D02*
X59575Y186000D01*
Y183000D01*
G01X65301Y187762D02*
X63982Y186443D01*
X60782D01*
X60400Y186825D01*
G01X59700Y196200D02*
X59500Y196000D01*
Y190875D01*
X60400Y189975D01*
G01X52000Y230400D02*
X53740D01*
X55240Y228900D01*
Y226076D01*
G01X63300Y241363D02*
Y237600D01*
G01Y249237D02*
Y257725D01*
G01X49938Y305721D02*
X51619D01*
X53120Y304220D01*
Y287820D01*
X50900Y285600D01*
Y270434D01*
X54300Y267034D01*
Y257545D01*
X52440Y255685D01*
G01X65800Y260875D02*
X63300D01*
G01Y257725D02*
X63975Y258400D01*
X67399D01*
X68799Y257000D01*
X68990D01*
G01X51500Y258200D02*
X51875Y258575D01*
Y260800D01*
G01X62458Y346425D02*
X60864Y344831D01*
G01X62458Y390481D02*
X64014Y388925D01*
G01X51823Y416096D02*
X54196D01*
X56275Y418175D01*
X66250D01*
G01X59303Y421214D02*
X66139D01*
X66250Y421325D01*
G01X56476Y466378D02*
Y460100D01*
G01X71369Y163879D02*
Y165730D01*
X70580Y166519D01*
Y167179D01*
G01X66251Y172541D02*
X66248Y172538D01*
Y170349D01*
X67330Y169267D01*
G01X65500Y180725D02*
Y178575D01*
X66251Y177824D01*
Y172541D01*
G01X65500Y183875D02*
X65786D01*
X67342Y185431D01*
Y186270D01*
X67486Y186414D01*
G01X72500Y261575D02*
X71175Y262900D01*
X67825D01*
X65800Y260875D01*
G01X64567Y315493D02*
Y306665D01*
G01X76500Y328055D02*
Y325500D01*
G01X70313Y354280D02*
X68757Y352724D01*
G01X73462Y357429D02*
X71906Y355873D01*
G01X75056Y359023D02*
X76612Y360579D01*
G01X67163Y351130D02*
X65607Y349574D01*
G01D02*
X64014Y347981D01*
G01X71906Y352724D02*
X73462Y354280D01*
G01X68757Y355873D02*
X70313Y357429D01*
G01X75056Y377883D02*
X76612Y376327D01*
G01X78206Y374733D02*
X79762Y373177D01*
G01X78206Y362173D02*
X79762Y363729D01*
G01X78206Y371584D02*
X79762Y370028D01*
G01X68757Y384182D02*
X70313Y382626D01*
G01X65607Y387332D02*
X67163Y385776D01*
G01X75018Y381033D02*
X73462Y379477D01*
G01X71869Y381033D02*
X70313Y379477D01*
G01X71906Y384182D02*
X73462Y382626D01*
G01X66250Y418175D02*
X67532D01*
X69057Y419700D01*
G01X77736Y466378D02*
Y460336D01*
X77500Y460100D01*
G01X70650Y466378D02*
Y460100D01*
G01X63563Y466378D02*
Y460100D01*
G01X91925Y119021D02*
X91834Y119112D01*
X89691D01*
X89679Y119100D01*
X86700D01*
G01X91925Y122171D02*
Y125925D01*
X93000Y127000D01*
X94500D01*
G01X87500Y241363D02*
Y237300D01*
G01X86500Y258725D02*
Y256575D01*
X87500Y255575D01*
Y249237D01*
G01X84000Y261375D02*
X86000D01*
X86500Y261875D01*
G01X93500Y262075D02*
X93409Y261984D01*
X91266D01*
X91157Y261875D01*
X88825D01*
X88734Y261784D01*
X86591D01*
X86500Y261875D01*
G01X90800Y258225D02*
X87000D01*
X86500Y258725D01*
G01X93916Y359023D02*
X92360Y360579D01*
G01X93916Y377883D02*
X92360Y376327D01*
G01X81355Y365322D02*
X82911Y366878D01*
G01X87617Y365322D02*
X86061Y366878D01*
G01X81355Y371584D02*
X82911Y370028D01*
G01X87617Y371584D02*
X86061Y370028D01*
G01X90766Y374733D02*
X89210Y373177D01*
G01X90766Y362173D02*
X89210Y363729D01*
G01X81355Y362173D02*
X82911Y363729D01*
G01X87617Y362173D02*
X86061Y363729D01*
G01X81355Y374733D02*
X82911Y373177D01*
G01X87617Y374733D02*
X86061Y373177D01*
G01X90766Y371584D02*
X89210Y370028D01*
G01X90766Y365322D02*
X89210Y366878D01*
G01X92825Y412500D02*
X95280D01*
G01X92825Y417000D02*
Y412500D01*
G01X78800Y423800D02*
X79930Y422670D01*
X81151D01*
X82781Y421040D01*
X83081D01*
G01X91909Y466378D02*
Y458275D01*
G01X84823Y466378D02*
Y460100D01*
G01X104425Y80000D02*
Y82500D01*
G01X107925Y107500D02*
X105916Y109509D01*
Y109952D01*
G01X108727Y99153D02*
X107925Y99955D01*
Y102000D01*
G01X100000Y96075D02*
Y98500D01*
G01X94500Y127000D02*
X96001D01*
X96503Y126498D01*
Y124509D01*
X95800Y123806D01*
Y122175D01*
G01D02*
X95891Y122084D01*
X97514D01*
X97518Y122080D01*
X97982D01*
X97986Y122084D01*
X99609D01*
X99700Y122175D01*
G01X96400Y135075D02*
Y137475D01*
G01X126575Y131000D02*
Y131624D01*
X123299Y134900D01*
X113000D01*
X110837Y132737D01*
X107424Y131322D01*
X105950Y129848D01*
Y126750D01*
X109200Y123500D01*
G01X95500Y269425D02*
X99500D01*
G01X103500D02*
X99500D01*
G01X103500D02*
Y268616D01*
X102600Y267716D01*
Y267000D01*
G01X103100Y328125D02*
X105349D01*
X105755Y327719D01*
G01X106564Y346400D02*
X108108Y344856D01*
Y344831D01*
G01X100215Y352724D02*
X98659Y354280D01*
G01X104958Y347981D02*
X103383Y349556D01*
G01X97066Y355873D02*
X95510Y357429D01*
G01X103383Y349556D02*
X101809Y351130D01*
G01X97066Y352724D02*
X95510Y354280D01*
G01X100215Y355873D02*
X98659Y357429D01*
G01X100215Y384182D02*
X98659Y382626D01*
G01X101809Y385776D02*
X103383Y387350D01*
G01X97066Y381033D02*
X95510Y379477D01*
G01X103383Y387350D02*
X104958Y388925D01*
G01X100215Y387332D02*
X98659Y385776D01*
G01X100215Y381033D02*
X98659Y379477D01*
G01X98680Y428525D02*
X99600D01*
X101100Y427025D01*
Y421500D01*
X102600Y420000D01*
X103400D01*
G01X98996Y466378D02*
Y458275D01*
G01X106083Y466378D02*
Y458275D01*
G01X108776Y47760D02*
X111000Y45536D01*
Y44600D01*
G01X112500Y42075D02*
X111000Y43575D01*
Y44600D01*
G01X122500Y58000D02*
Y58799D01*
X121882Y59417D01*
Y61037D01*
G01X116560Y85451D02*
Y88651D01*
G01X115025Y102000D02*
Y104800D01*
G01D02*
Y107600D01*
G01X120726Y105000D02*
X123376D01*
G01X116560Y94900D02*
Y96840D01*
X115200Y98200D01*
G01X123376Y122500D02*
X121726D01*
X120726Y123500D01*
X120626D01*
G01X114425D02*
X112000D01*
G01X109200D02*
X112000D01*
G01X118300Y237500D02*
X118574Y237774D01*
X123890D01*
X126376Y240260D01*
G01X110800Y257125D02*
Y255280D01*
X111400Y254680D01*
G01X114800Y257725D02*
X111400D01*
X110800Y257125D01*
G01X114800Y257725D02*
X115097D01*
X112800Y252179D01*
Y249540D01*
G01X121720Y265330D02*
X119554D01*
X118374Y264150D01*
X117051D01*
X114800Y261899D01*
Y260875D01*
G01X121918Y331563D02*
X125918D01*
G01X119075Y415000D02*
Y413017D01*
X119791Y412301D01*
G01X125260Y44459D02*
X127400D01*
X127900Y44959D01*
Y45000D01*
G01X129575Y54300D02*
Y57375D01*
G01X136319Y89055D02*
X140869D01*
G01X126200Y82575D02*
X125925Y82300D01*
X123710D01*
G01X136319Y104803D02*
X140869D01*
G01X136319Y96929D02*
X141700D01*
G01X123376Y105000D02*
X126378D01*
G01Y122500D02*
X123376D01*
G01X129328D02*
X126378D01*
G01X126575Y114000D02*
Y111416D01*
G01X136319Y120551D02*
X140869D01*
G01X136319Y112677D02*
X140869D01*
G01X136319Y120551D02*
X133449D01*
X131900Y122100D01*
X129728D01*
X129328Y122500D01*
G01X126575Y131000D02*
X131700D01*
G01X146260Y129606D02*
X136304D01*
X134910Y131000D01*
X131700D01*
G01X133500Y152985D02*
Y149385D01*
G01X133000Y176575D02*
X129000D01*
G01D02*
X126300D01*
G01X126500Y256775D02*
X128023D01*
X128900Y255898D01*
G01D02*
X128902D01*
X130425Y254375D01*
Y253700D01*
G01X145130Y257010D02*
X141240Y260900D01*
X133775D01*
X132775Y261900D01*
G01X124260Y276126D02*
Y274560D01*
X125100Y273720D01*
G01X137918Y331563D02*
X141918D01*
G01X125918D02*
Y334998D01*
X125910Y335006D01*
G01X129300Y425925D02*
Y424250D01*
X128970Y423453D01*
Y416513D01*
X129900Y415583D01*
G01X139900Y428925D02*
X136250D01*
X136175Y429000D01*
G01X136230Y423935D02*
X136083Y424082D01*
Y428908D01*
X136175Y429000D01*
G01X129300Y429075D02*
Y429571D01*
X131960Y432231D01*
Y433000D01*
X132070Y433110D01*
G01X141949Y466378D02*
Y460012D01*
X142570Y459391D01*
Y446595D01*
X132890Y436915D01*
Y433930D01*
X132070Y433110D01*
G01X146260Y72126D02*
X149500Y75366D01*
Y96127D01*
X145199Y100428D01*
G01Y118699D02*
Y100428D01*
G01D02*
X141700Y96929D01*
G01X146260Y129606D02*
Y119760D01*
X145199Y118699D01*
G01D02*
X142721D01*
X140869Y120551D01*
G01X141500Y143575D02*
Y145500D01*
X142000Y146000D01*
G01X145500Y143575D02*
Y148225D01*
X143269Y150456D01*
G01D02*
X146103Y153290D01*
X148387D01*
G01X152434D02*
Y154265D01*
X150934Y155765D01*
X148400D01*
G01X155641Y178679D02*
X153323D01*
X153216Y178572D01*
X153134D01*
G01X145130Y257010D02*
Y280830D01*
X149100Y284800D01*
X152000D01*
X152400Y284400D01*
G01X145250Y256890D02*
X145130Y257010D01*
G01X142300Y275625D02*
X141100Y274425D01*
Y268815D01*
X142780Y267135D01*
Y266830D01*
G01X146063Y315493D02*
X150293D01*
G01X141918Y331563D02*
X142202Y331847D01*
Y334000D01*
G01X142500Y345800D02*
Y347128D01*
X143945Y348573D01*
G01X139975Y348300D02*
X139776Y348101D01*
Y346896D01*
X138590Y345710D01*
G01X153918Y331563D02*
X153695D01*
X151158Y334100D01*
X150800D01*
X148600Y336300D01*
G01X147900Y348525D02*
X143993D01*
X143945Y348573D01*
G01Y351723D02*
Y354146D01*
G01X152100Y425700D02*
X150425Y427375D01*
Y429000D01*
G01X145200Y432525D02*
X145350D01*
X146225Y433400D01*
X148100D01*
G01D02*
X149725D01*
X150525Y432600D01*
G01X149035Y466378D02*
Y458756D01*
X149041Y458750D01*
G01X166719Y73224D02*
Y70222D01*
G01Y73224D02*
Y75874D01*
G01X159120Y119045D02*
Y117310D01*
X158420Y116610D01*
G01X159700Y112000D02*
X159900D01*
X160700Y112800D01*
X163225D01*
G01X155534Y182644D02*
Y178786D01*
X155641Y178679D01*
G01X159932Y212568D02*
Y216544D01*
X160032Y216644D01*
G01X166308Y225189D02*
X168411D01*
X170000Y223600D01*
Y221300D01*
X164921Y216221D01*
X160455D01*
X160032Y216644D01*
G01X157500Y232075D02*
Y233199D01*
X155999Y234700D01*
X155800D01*
G01X163690Y268610D02*
X163387Y268307D01*
X161894D01*
X160559Y269642D01*
Y273711D01*
G01X158374Y313560D02*
Y309701D01*
X158375Y309700D01*
G01X165026Y343621D02*
X164714Y343309D01*
Y341186D01*
X164800Y341100D01*
X164790D01*
G01X169669Y399419D02*
X168012Y401076D01*
Y404370D01*
G01D02*
X168013Y404371D01*
Y405749D01*
G01X157600Y432575D02*
X161450D01*
G01D02*
Y433849D01*
X159676Y435623D01*
X157294D01*
G01X160846Y465590D02*
Y460124D01*
X160852Y460118D01*
G01X172632Y119951D02*
X177886D01*
X178186Y119651D01*
G01X172632Y119951D02*
X168616D01*
G01X179500Y116800D02*
Y117200D01*
X178186Y118514D01*
Y119651D01*
G01X184525Y294500D02*
X184099Y294074D01*
X181194D01*
G01X169026Y343621D02*
X168557Y343152D01*
Y341221D01*
G01X182750Y426750D02*
X181400Y428100D01*
Y429625D01*
G01X174425Y432600D02*
Y431365D01*
X172530Y429470D01*
G01X171276Y426771D02*
Y428216D01*
X172530Y429470D01*
G01X187272Y82028D02*
Y84472D01*
G01X191312Y82028D02*
Y84512D01*
G01X182925Y88000D02*
Y84300D01*
G01X193096Y115600D02*
X195900Y118404D01*
Y119786D01*
X196065Y119951D01*
G01X186201Y158155D02*
X187794Y159748D01*
G01X192500Y173903D02*
X190944Y172347D01*
G01X192500Y177052D02*
X190944Y175496D01*
G01X198799Y177052D02*
X197243Y175496D01*
G01X192500Y180202D02*
X190944Y178646D01*
G01X192500Y183351D02*
X190944Y181795D01*
G01X198799Y183351D02*
Y183389D01*
X197243Y184945D01*
G01X192500Y195950D02*
X190944Y197506D01*
G01X192500Y189651D02*
X190944Y188095D01*
G01X192500Y192800D02*
X190944Y191244D01*
G01X192500Y186501D02*
X190944Y184945D01*
G01X189350Y192800D02*
Y195950D01*
G01Y186501D02*
X187794Y184945D01*
G01X198799Y205399D02*
Y205361D01*
X197243Y203805D01*
G01X192500Y202249D02*
Y202211D01*
X190944Y200655D01*
G01X192500Y199099D02*
X190944Y200655D01*
G01X192500Y205399D02*
X190944Y203843D01*
Y203805D01*
G01X183413Y250136D02*
X183613Y249936D01*
X185897D01*
G01X193925Y264810D02*
X193905Y264790D01*
Y261090D01*
X193995Y261000D01*
Y260830D01*
G01X196525Y268700D02*
Y270508D01*
X195370Y273297D01*
G01X190900Y271700D02*
X190075Y270875D01*
Y267000D01*
G01X189125Y311100D02*
Y310720D01*
X185725Y307320D01*
G01X195000Y373900D02*
X193750Y372650D01*
Y371325D01*
G01Y376425D02*
X195000Y375175D01*
Y373900D01*
G01X193750Y385425D02*
X197620D01*
G01X189762Y429177D02*
X192334D01*
G01X190807Y465590D02*
Y461507D01*
X189600Y460300D01*
Y459800D01*
G01X205969Y92326D02*
X209500D01*
G01X214500Y94075D02*
X211975D01*
X211800Y93900D01*
Y93870D01*
G01X210778Y108769D02*
Y107120D01*
X209824Y106166D01*
Y106122D01*
G01X214464Y119951D02*
X210189D01*
G01D02*
Y118181D01*
X211370Y117000D01*
G01X205098Y183351D02*
X205136D01*
X206692Y181795D01*
G01X208248Y183351D02*
X206692Y181795D01*
G01X201949Y177052D02*
X200393Y175496D01*
G01X201949Y183351D02*
X198799D01*
G01Y208548D02*
X198837D01*
X200393Y210104D01*
G01X205098Y205399D02*
X203542Y206955D01*
G01X208248Y205399D02*
X206692Y206955D01*
G01X211398Y205399D02*
X209842Y206955D01*
G01X201949Y205399D02*
X200393Y206955D01*
G01X211398Y217997D02*
X211435D01*
X212991Y219553D01*
G01X201949Y230595D02*
X200393Y232151D01*
G01X210988Y304635D02*
X209030D01*
X207220Y302825D01*
Y301180D01*
G01X207750Y361100D02*
Y366500D01*
G01X208360Y384890D02*
X207595Y384125D01*
Y378154D01*
G01X198600Y426600D02*
Y428372D01*
X199405Y429177D01*
G01D02*
X203348D01*
X203400Y429125D01*
G01X228832Y107236D02*
X224958D01*
G01X217495Y97984D02*
Y96670D01*
X214900Y94075D01*
X214500D01*
G01X220846Y180202D02*
X222402Y178646D01*
G01X220846Y177052D02*
Y177090D01*
X222402Y178646D01*
G01X223996Y189651D02*
X225552Y188095D01*
G01D02*
X227146Y186501D01*
G01D02*
X230295D01*
G01X223996Y192800D02*
X225552Y191244D01*
G01X223996Y195950D02*
Y192800D01*
G01X214547Y189651D02*
Y186501D01*
G01D02*
X212991Y184945D01*
G01X214547Y195950D02*
X212991Y197506D01*
G01X214547Y192800D02*
Y195950D01*
G01X217697D02*
Y192800D01*
G01X220846Y199099D02*
Y199062D01*
X222402Y197506D01*
G01X220846Y195950D02*
X222402Y197506D01*
G01X219253D02*
X217697Y195950D01*
G01X227146Y211698D02*
X227183D01*
X228739Y213254D01*
G01X227146Y205399D02*
X227659Y205912D01*
X229782D01*
X230295Y205399D01*
G01X214547Y202249D02*
X212991Y203805D01*
G01X214547Y199099D02*
X212991Y200655D01*
G01X214547Y211698D02*
X212991Y213254D01*
G01X226075Y296600D02*
Y300600D01*
G01D02*
X226700D01*
X228800Y302700D01*
G01X223565Y372400D02*
Y370825D01*
X224565Y369825D01*
X224632D01*
G01X225700Y362500D02*
X226330Y361870D01*
X228910D01*
X232615Y365575D01*
X238551D01*
G01X222800Y379350D02*
Y382505D01*
X223555Y383260D01*
G01X220515Y384900D02*
X222055D01*
X223555Y383400D01*
Y383260D01*
G01X233000Y44575D02*
Y47100D01*
G01X242200Y119925D02*
X242812Y119313D01*
Y117501D01*
G01X238382Y119951D02*
X237127Y118696D01*
Y116573D01*
X238900Y114800D01*
G01X242195Y134794D02*
Y132805D01*
X242800Y132200D01*
G01X239744Y170753D02*
X237656Y172841D01*
X235533D01*
X233445Y170753D01*
G01X239744Y183351D02*
Y180202D01*
G01D02*
X241300Y178646D01*
G01X239744Y177052D02*
X241300Y175496D01*
G01X239744Y173903D02*
X241300Y172347D01*
G01X235001Y188095D02*
X233445Y189651D01*
G01Y192800D02*
X235001Y191244D01*
G01X233445Y195950D02*
X235001Y197506D01*
G01X239744Y195950D02*
X237464Y193670D01*
Y188781D01*
X239744Y186501D01*
G01D02*
X241300Y184945D01*
G01Y197506D02*
X239744Y195950D01*
G01Y189651D02*
X241300Y188095D01*
G01X233445Y211698D02*
X233901Y212154D01*
X239288D01*
X239744Y211698D01*
G01Y202249D02*
Y202211D01*
X241300Y200655D01*
G01X239744Y199099D02*
X241300Y200655D01*
G01X230295Y208548D02*
X231851Y210104D01*
G01X241300Y213254D02*
X241338D01*
X242894Y211698D01*
G01X239744Y214847D02*
X238152D01*
X236594Y216405D01*
Y217997D01*
G01X235001Y219553D02*
X235038D01*
X236594Y217997D01*
G01X229625Y258200D02*
Y259700D01*
X231125Y261200D01*
X232300D01*
G01X238500Y331925D02*
Y329600D01*
X240000Y328100D01*
X241400D01*
G01X242500Y340425D02*
X246000Y336925D01*
Y330500D01*
X243600Y328100D01*
X241400D01*
G01X233300Y356890D02*
X246803D01*
X246858Y356835D01*
G01Y390063D02*
X233855D01*
X233800Y390118D01*
G01X238551Y381323D02*
X243410D01*
G01X245760Y46559D02*
X248359D01*
G01X264913Y79500D02*
X257900D01*
X255750Y77350D01*
G01X243700Y106025D02*
Y104815D01*
X244987Y103528D01*
G01X247200Y117400D02*
X246000Y118600D01*
Y119925D01*
G01X242894Y192800D02*
X244450Y191244D01*
G01X253388Y268403D02*
Y273655D01*
G01X250238Y268403D02*
X247708Y265873D01*
Y263492D01*
G01X246873Y257365D02*
Y262657D01*
X247708Y263492D01*
G01X250288Y273581D02*
Y268453D01*
X250238Y268403D01*
G01X250575Y322000D02*
Y313500D01*
G01D02*
X253400D01*
X262930Y323030D01*
Y325300D01*
G01X261418Y12166D02*
X267022D01*
G01X269095Y34625D02*
Y29095D01*
G01X264500Y42441D02*
X260970D01*
G01X259500Y101100D02*
X260575D01*
X262075Y102600D01*
Y110300D01*
G01X268435Y121476D02*
X267326Y122585D01*
Y127525D01*
G01X271602Y121400D02*
X271066Y120864D01*
Y118077D01*
G01X279582Y245577D02*
X272237D01*
X272037Y245377D01*
G01X269400Y284575D02*
Y297400D01*
X268900Y297900D01*
X266250D01*
G01X265100Y424000D02*
X265375Y423725D01*
X268000D01*
G01X277000Y44425D02*
Y41982D01*
G01X286000Y51941D02*
X282440D01*
G01X286000Y65575D02*
Y67975D01*
G01X285000Y75925D02*
X281000D01*
G01D02*
X277000D01*
G01X277200Y115925D02*
X277275D01*
X279100Y114100D01*
X279200D01*
G01X277049Y131629D02*
X274500D01*
G01X279582Y245577D02*
X282523D01*
X286000Y242100D01*
G01X288000Y294075D02*
X283576D01*
X281889Y292388D01*
Y287636D01*
G01X284475Y375083D02*
Y375400D01*
X285975Y376900D01*
X287500D01*
G01X275700Y403500D02*
X273075Y400875D01*
Y399500D01*
G01X276614Y466378D02*
Y460977D01*
X277563Y460028D01*
G01X283701Y466378D02*
Y459404D01*
X283707Y459398D01*
G01X306300Y10591D02*
X300600D01*
G01X294488Y12166D02*
X288856D01*
G01X295402Y45224D02*
Y48051D01*
G01X290245Y44578D02*
Y46978D01*
G01X293000Y57059D02*
X300366D01*
X300425Y57000D01*
G01X290000Y65575D02*
Y67975D01*
G01X300856Y104059D02*
X297821Y107094D01*
Y108055D01*
G01X291380Y112161D02*
Y111821D01*
X293901Y109300D01*
X296576D01*
X297821Y108055D01*
G01Y122106D02*
X295486D01*
X291380Y126212D01*
G01X304259Y112161D02*
X303761D01*
X301151Y109551D01*
Y108649D01*
G01X294685Y142907D02*
Y140792D01*
X297180Y138297D01*
G01X301936Y138197D02*
Y135797D01*
G01X291380Y126212D02*
X291612D01*
X294200Y128800D01*
G01X297180Y138297D02*
X301936D01*
Y138197D01*
G01Y146297D02*
Y143897D01*
G01X300575Y307000D02*
X302575Y305000D01*
X304000D01*
G01X301500Y330618D02*
Y326500D01*
G01X290150Y358508D02*
Y363008D01*
G01X293300D02*
Y358508D01*
G01D02*
X294000D01*
X295500Y357008D01*
Y354920D01*
G01X290150Y363008D02*
X289750Y363408D01*
X287790D01*
X287725Y363473D01*
G01X303512Y365575D02*
X301845D01*
X299278Y363008D01*
X293300D01*
G01X290150Y367508D02*
X288842Y366200D01*
X287761D01*
G01X311819Y390063D02*
X298803D01*
X298748Y390118D01*
G01X339370Y10591D02*
X306300D01*
G01X313977Y27520D02*
Y33400D01*
G01X303575Y57000D02*
Y54516D01*
G01X310661Y108055D02*
X308365D01*
X304259Y112161D01*
G01X310661Y122106D02*
Y123500D01*
X309161Y125000D01*
X308135D01*
X307500Y125635D01*
G01X304259Y126212D02*
X304277Y126230D01*
X306905D01*
X307500Y125635D01*
G01X305936Y146297D02*
Y143897D01*
G01X309936Y146297D02*
Y143897D01*
G01X313936Y146297D02*
Y143897D01*
G01X312804Y193336D02*
X314307Y194839D01*
G01X303077Y294789D02*
Y297519D01*
G01X308075Y311500D02*
Y313575D01*
X309500Y315000D01*
G01X311000Y323425D02*
Y320500D01*
G01X311819Y356835D02*
X324983D01*
X325038Y356890D01*
G01X311819Y390063D02*
X325265D01*
X325320Y390118D01*
G01X317936Y149447D02*
X319564Y151075D01*
X320239D01*
G01X322000Y148075D02*
Y149314D01*
X320239Y151075D01*
G01X333278Y148439D02*
X329202D01*
G01X317936Y146297D02*
Y143897D01*
G01X332174Y286352D02*
X333828D01*
G01X329997Y283191D02*
X333817D01*
X333828Y283202D01*
G01X329825Y278972D02*
X327162D01*
G01X329825Y275822D02*
X333839D01*
G01X335516Y289095D02*
X343541D01*
X346007Y286629D01*
Y235348D01*
X344291Y233632D01*
X337223D01*
G01X330900Y317325D02*
Y314700D01*
G01X337375Y74000D02*
Y76600D01*
G01Y70000D02*
X339000D01*
X339900Y69100D01*
G01X333278Y151129D02*
Y148439D01*
G01X337400Y183926D02*
Y184411D01*
X338900Y185911D01*
X339800D01*
G01X333828Y286352D02*
X336312D01*
G01X333839Y278972D02*
Y283191D01*
X333828Y283202D01*
G01D02*
X336461D01*
G01X337600Y278975D02*
X337603Y278972D01*
X340612D01*
G01X333839Y275822D02*
X337597D01*
X337600Y275825D01*
G01X336875Y295900D02*
X339700D01*
G01Y293000D02*
X337814D01*
X336899Y292085D01*
G54D122*
X377576Y-165691D03*
X377604Y62581D03*
X408750Y-70872D03*
X398750Y258400D03*
G54D104*
X161877Y107140D03*
Y103400D03*
Y99660D03*
X171523D03*
Y107140D03*
G54D20*
X16608Y187453D03*
X18000Y230117D03*
X42281Y203275D03*
X46307D03*
X40500Y231017D03*
X48440Y252627D03*
X40500Y371017D03*
Y364017D03*
Y378017D03*
Y399517D03*
X48600Y429017D03*
X44700D03*
X52500Y63017D03*
X63918Y123172D03*
X60090Y123177D03*
X61216Y225817D03*
X52440Y252627D03*
X63300Y257817D03*
X49938Y305813D03*
X55800Y328017D03*
X52500Y429017D03*
X56500D03*
X69200Y180817D03*
X65500D03*
X73400Y219717D03*
X77500D03*
X65216Y225817D03*
X75400Y229917D03*
X72500Y258517D03*
X67000Y403017D03*
X71000D03*
X88083Y121989D03*
X81500Y219717D03*
X91500Y269517D03*
X93500Y259017D03*
X86500Y258817D03*
X90804Y330337D03*
X79000Y403017D03*
X102800Y85017D03*
X100000Y93017D03*
X99700Y119117D03*
X95800D03*
X100400Y132017D03*
X96400D03*
X106800Y256617D03*
X99500Y269517D03*
X107400Y270417D03*
X103500Y269517D03*
X95500D03*
X103100Y328217D03*
X98000D03*
X98680Y425467D03*
X120500Y39017D03*
X112500D03*
X110800Y257217D03*
X119760Y268218D03*
X115260D03*
X111500Y268017D03*
X114800Y257817D03*
X111100Y276217D03*
X115260Y276218D03*
X119760D03*
X117918Y328505D03*
X113918D03*
X118800Y354217D03*
X129500Y141017D03*
X137525Y140844D03*
X133500Y141017D03*
X133000Y173517D03*
X129000D03*
X126500Y253717D03*
X124500Y261217D03*
X128760Y268218D03*
X124260D03*
X133000Y268017D03*
X124260Y276218D03*
X128760D03*
X129918Y328505D03*
X133918D03*
X141500Y140517D03*
X152434Y150232D03*
X141500Y238517D03*
X145918Y328505D03*
X149918D03*
X139900Y429017D03*
X155300Y101317D03*
X155530Y119137D03*
X164400Y120017D03*
X168000Y135017D03*
X160457Y142526D03*
X156430Y142498D03*
X160500Y202617D03*
X156028Y216736D03*
X157500Y229017D03*
X156973Y249528D03*
X160713Y257546D03*
X156713D03*
X165013Y249528D03*
X155000Y289517D03*
X165200Y317517D03*
X161026Y343713D03*
X178000Y104317D03*
X172632Y120043D03*
X168616D03*
X178186Y119743D03*
X180000Y134817D03*
X176000D03*
X178174Y258038D03*
X169026Y343713D03*
X173026D03*
X187272Y78970D03*
X191312D03*
X196065Y120043D03*
X191400D03*
X184000Y134917D03*
X183350Y259297D03*
X188000Y317917D03*
X193750Y360767D03*
Y376517D03*
Y385517D03*
X192334Y429269D03*
X211000Y41017D03*
X200000Y120017D03*
X210189Y120043D03*
X204000Y120017D03*
X199985Y134886D03*
X204120D03*
X207912Y250141D03*
X199810Y250303D03*
X209500Y273017D03*
X199405Y429269D03*
X203400Y429217D03*
X219000Y41017D03*
X214500Y91017D03*
X223300Y120017D03*
X214464Y120043D03*
X218200Y249117D03*
X221800D03*
X222300Y279117D03*
X221260Y310377D03*
X220600Y318017D03*
X226650Y376327D03*
X213500Y376517D03*
X237000Y41517D03*
X233000D03*
X242200Y120017D03*
X228600D03*
X238382Y120043D03*
X233511Y135086D03*
X242195Y134886D03*
X237655D03*
X239100Y250717D03*
X235100D03*
X228500Y332017D03*
Y344817D03*
X246000Y120017D03*
X252400Y277427D03*
X254010Y423731D03*
X265900Y110017D03*
X261300Y250317D03*
X268000Y423817D03*
X286000Y41517D03*
X281500D03*
X286000Y62517D03*
X277000Y76017D03*
X281000D03*
X285000D03*
X277300Y105917D03*
X285295Y110903D03*
Y128484D03*
X278028Y137331D03*
X272698Y137341D03*
X277049Y128571D03*
X284100Y416817D03*
X290245Y41520D03*
X301936Y138289D03*
X288000Y291017D03*
X316066Y110902D03*
X313936Y138389D03*
X309936D03*
X305936D03*
X303077Y291731D03*
X307087D03*
X320872Y117219D03*
X317936Y146389D03*
X322000Y145017D03*
X333278Y145381D03*
X333839Y275914D03*
X333828Y283294D03*
X332500Y300317D03*
X336500D03*
G54D11*
X-23737Y543288D03*
X-16737Y536288D03*
X-16500Y544500D03*
X6590Y264520D03*
X10000Y123500D03*
X7800Y194400D03*
X10800Y234200D03*
X15500Y252000D03*
X10500Y245400D03*
X25600Y106300D03*
X36292Y208592D03*
X50700Y439100D03*
X62321Y69200D03*
X62259Y211100D03*
X54975Y215900D03*
X62520Y233600D03*
X55240Y243700D03*
X58800Y265000D03*
X63945Y427055D03*
X71589Y118250D03*
X67400Y155600D03*
X76000Y175100D03*
X81000Y212330D03*
X70289Y227521D03*
X80200Y234100D03*
X67699Y235380D03*
X69187Y429000D03*
X94500Y127000D03*
X83950Y134950D03*
X86000Y147700D03*
X92200Y141540D03*
X85794Y227069D03*
X84941Y232100D03*
X89675Y421940D03*
X88565Y433040D03*
X105030Y96300D03*
X109800Y422300D03*
X103070Y432630D03*
X110200Y431600D03*
X124000Y50100D03*
X124801Y148130D03*
X123906Y188194D03*
X121200Y234890D03*
X119600Y261500D03*
X137540Y169500D03*
X129810Y191310D03*
X132398Y232400D03*
X132100Y346600D03*
X148314Y193687D03*
X155500Y200500D03*
X153000Y348600D03*
X164982Y164842D03*
X164472Y169902D03*
X164601Y181492D03*
X164426Y174982D03*
X165000Y191807D03*
X164879Y186543D03*
X164800Y198000D03*
X163500Y229184D03*
X167500Y312500D03*
X160500Y318500D03*
X166000Y305500D03*
X169600Y432670D03*
X166450Y424810D03*
X161120Y424590D03*
X181595Y142905D03*
X183500Y245500D03*
X181750Y337300D03*
X178300Y348600D03*
X179800Y423989D03*
X190912Y90313D03*
X191100Y96066D03*
X198703Y143302D03*
X186800Y142800D03*
X192194Y142712D03*
X190708Y245541D03*
X196170Y245552D03*
X188500Y274900D03*
X192500Y278000D03*
X192380Y291900D03*
X191199Y300200D03*
X191230Y305500D03*
X188546Y326356D03*
X200274Y410960D03*
X200048Y418652D03*
X195000Y422540D03*
X186720Y432490D03*
X212872Y48793D03*
X211400Y59238D03*
X200900Y110800D03*
X206200Y102200D03*
X214814Y142700D03*
X203703Y143307D03*
X202600Y245500D03*
X213000Y250500D03*
X206440Y261171D03*
X214034Y261482D03*
X205900Y266130D03*
X204207Y278200D03*
X213700Y363100D03*
X208300Y398150D03*
X202674Y404600D03*
X208830Y424500D03*
X229900Y61000D03*
X227547Y74275D03*
X215900Y73800D03*
X227760Y82524D03*
X217262Y129294D03*
X224784Y142600D03*
X219800Y143250D03*
X230400Y249600D03*
X220866Y272160D03*
X226405Y266335D03*
X229220Y283250D03*
X217400Y295200D03*
X217673Y300600D03*
X228300Y319400D03*
X218100Y305600D03*
X226075Y309390D03*
X228230Y340040D03*
X219800Y364200D03*
X224101Y352320D03*
X226428Y411600D03*
X233400Y123100D03*
X241900Y114300D03*
X233511Y129594D03*
Y142983D03*
X241100Y245510D03*
X244150Y250920D03*
X235326Y245472D03*
X235006Y263591D03*
X234500Y293500D03*
X237900Y324300D03*
X237500Y343000D03*
X235370Y403500D03*
X241231Y407285D03*
X257145Y279700D03*
X257900Y312100D03*
X249400Y410300D03*
X251800Y416600D03*
X257900Y416700D03*
X256400Y431500D03*
X250800Y432500D03*
X264989Y101732D03*
X271500Y111600D03*
X267204Y185566D03*
X274835Y189927D03*
X262100Y280700D03*
X268170Y359840D03*
X273580Y354250D03*
X272581Y376280D03*
X268200Y373400D03*
Y390100D03*
X274880Y387292D03*
X260300Y403370D03*
X270000Y431600D03*
X261400Y433100D03*
X280125Y55200D03*
X280293Y60430D03*
X289736Y78607D03*
X280270Y88470D03*
X284222Y103300D03*
X275528Y163811D03*
X281889Y287636D03*
X285911Y279569D03*
X286372Y320700D03*
X288200Y348300D03*
X276400Y370400D03*
X285500Y426100D03*
X278400Y426400D03*
X284200Y432900D03*
X293773Y73530D03*
X302091Y74553D03*
X291720Y95610D03*
X298575Y101900D03*
X303600Y132200D03*
X302001Y242900D03*
X298100Y283900D03*
X290120Y339370D03*
X290501Y377400D03*
X290450Y382690D03*
X315080Y95980D03*
X310768Y102012D03*
X307101Y249100D03*
X313763Y274756D03*
X312300Y340700D03*
X328000Y62100D03*
X322500Y102900D03*
X320779Y111030D03*
X327383Y164347D03*
X327830Y174403D03*
X324777Y182042D03*
X328265Y187045D03*
X328100Y293800D03*
X341000Y61300D03*
X345195Y105845D03*
X343600Y118900D03*
X337004Y202113D03*
Y210113D03*
G54D113*
X246858Y356835D03*
Y390063D03*
X311819Y356835D03*
Y390063D03*
G54D132*
G01X252342Y183351D02*
X253256Y182437D01*
G03X254671Y181851I1415J1415D01*
G01X262445D01*
G02X263494Y181416I-1J-1484D01*
G01X265075Y179835D01*
G02X265222Y179481I-354J-355D01*
G01Y178459D01*
G02X264750Y177319I-1613J0D01*
G01X264222Y176791D01*
G01X255492Y183351D02*
X262445D01*
G02X264555Y182477I0J-2984D01*
G01X266136Y180896D01*
G02X266722Y179481I-1415J-1415D01*
G01Y178459D01*
G03X267194Y177319I1613J0D01*
G01X267722Y176791D01*
G01X255492Y202249D02*
X258060D01*
G02X258560Y201749I0J-500D01*
G01Y200270D01*
G03X260460Y198370I1900J0D01*
G01X260957D01*
G02X262157Y197873I0J-1697D01*
G01X262314Y197716D01*
G03X263270Y197320I956J956D01*
G01X263350D01*
G03X264306Y197716I0J1352D01*
G01X264502Y197912D01*
G02X265607Y198370I1105J-1104D01*
G01X265686D01*
G02X266791Y197912I0J-1562D01*
G01X266987Y197716D01*
G03X267943Y197320I956J956D01*
G01X268023D01*
G03X268979Y197716I0J1352D01*
G01X269136Y197873D01*
G02X270336Y198370I1200J-1200D01*
G01X270833D01*
G02X272033Y197873I0J-1697D01*
G01X272190Y197716D01*
G03X273146Y197320I956J956D01*
G01X273226D01*
G03X274182Y197716I0J1352D01*
G01X274424Y197958D01*
G02X275418Y198370I994J-993D01*
G01X275458D01*
G03X277358Y200270I0J1900D01*
G01Y202215D01*
G03X275358Y204215I-2000J0D01*
G01X274207D01*
G02X273007Y204712I0J1697D01*
G01X272850Y204869D01*
G03X271894Y205265I-956J-956D01*
G01X271814D01*
G03X270858Y204869I0J-1352D01*
G01X270701Y204712D01*
G02X269501Y204215I-1200J1200D01*
G01X265484D01*
G02X264816Y204883I0J668D01*
G01Y206670D01*
G02X265408Y207262I592J0D01*
G01X266080D01*
G01X252342Y202249D02*
X253256Y203163D01*
G02X254671Y203749I1415J-1415D01*
G01X258060D01*
G02X260060Y201749I0J-2000D01*
G01Y200270D01*
G03X260460Y199870I400J0D01*
G01X275458D01*
G03X275858Y200270I0J400D01*
G01Y202215D01*
G03X275358Y202715I-500J0D01*
G01X265484D01*
G02X263316Y204883I0J2168D01*
G01Y206042D01*
G03X262976Y206865I-1166J0D01*
G01X262580Y207262D01*
G01X255492Y208548D02*
X257308D01*
G03X258420Y208888I-4J2001D01*
G01X259121Y209589D01*
G02X259483Y209740I363J-361D01*
G01X278627D01*
G03X280042Y210326I0J2001D01*
G01X280078Y210362D01*
G03X280665Y211779I-1417J1417D01*
G01Y217500D01*
G03X278645Y219520I-2020J0D01*
G01X268530D01*
X268510Y219500D01*
X267205D01*
G03X265790Y218914I0J-2002D01*
G01X265166Y218289D01*
G03X264580Y216875I1415J-1415D01*
G01Y216261D01*
G02X264108Y215121I-1613J0D01*
G01X263580Y214593D01*
G01X252342Y208548D02*
X253256Y209462D01*
G02X254671Y210048I1415J-1415D01*
G01X257306D01*
G03X257497Y210087I-3J501D01*
G01X258059Y210649D01*
G02X259481Y211240I1424J-1421D01*
G01X259643D01*
G03X260783Y211712I0J1613D01*
G01X260915Y211844D01*
G02X261871Y212240I956J-956D01*
G01X261951D01*
G02X262907Y211844I0J-1352D01*
G01X263115Y211636D01*
G03X264071Y211240I956J956D01*
G01X264151D01*
G03X265107Y211636I0J1352D01*
G01X265315Y211844D01*
G02X266271Y212240I956J-956D01*
G01X266351D01*
G02X267307Y211844I0J-1352D01*
G01X267515Y211636D01*
G03X268471Y211240I956J956D01*
G01X268551D01*
G03X269507Y211636I0J1352D01*
G01X269715Y211844D01*
G02X270671Y212240I956J-956D01*
G01X270751D01*
G02X271707Y211844I0J-1352D01*
G01X271839Y211712D01*
G03X272979Y211240I1140J1141D01*
G01X273338D01*
G03X274538Y211737I0J1697D01*
G01X274695Y211894D01*
G02X275651Y212290I956J-956D01*
G01X275731D01*
G02X276687Y211894I0J-1352D01*
G01X276844Y211737D01*
G03X278044Y211240I1200J1200D01*
G01X278627D01*
G03X278981Y211387I-1J501D01*
G01X279017Y211423D01*
G03X279165Y211779I-356J357D01*
G01Y212464D01*
G03X278755Y213453I-1398J0D01*
G01X278511Y213697D01*
G02X278115Y214653I956J956D01*
G01Y214928D01*
G02X278373Y215551I881J0D01*
G01X278668Y215846D01*
G03X279165Y217046I-1200J1200D01*
G01Y217500D01*
G03X278645Y218020I-520J0D01*
G01X277695D01*
G03X276495Y217523I0J-1697D01*
G01X276338Y217366D01*
G02X275382Y216970I-956J956D01*
G01X275302D01*
G02X274346Y217366I0J1352D01*
G01X274088Y217624D01*
G03X273132Y218020I-956J-956D01*
G01X273052D01*
G03X272096Y217624I0J-1352D01*
G01X271838Y217366D01*
G02X270882Y216970I-956J956D01*
G01X270802D01*
G02X269846Y217366I0J1352D01*
G01X269710Y217502D01*
G03X268509Y218000I-1202J-1201D01*
G01X267206D01*
G03X266852Y217853I1J-501D01*
G01X266227Y217228D01*
G03X266080Y216874I354J-355D01*
G01Y215759D01*
G03X266198Y215475I401J0D01*
G01X267080Y214593D01*
G01X249193Y221147D02*
X250749Y222703D01*
G01X249193Y224296D02*
X250749Y225852D01*
G01X252342Y217997D02*
X253898Y219553D01*
G01X252342Y221147D02*
X253898Y222703D01*
G01X293907Y196486D02*
X292404Y194983D01*
G01X293907Y193336D02*
X295410Y194839D01*
G01X309655Y183888D02*
X308152Y182385D01*
G01X306505Y183888D02*
X308008Y185391D01*
G01X306505Y212234D02*
X308008Y210731D01*
G01X306505Y209084D02*
X305002Y210587D01*
G01X451000Y-18000D02*
X447550D01*
X446750Y-18800D01*
Y-26185D01*
X444672Y-28263D01*
X426100D01*
X424900Y-29463D01*
Y-31863D01*
X426100Y-33063D01*
X470522D01*
X472600Y-35141D01*
Y-38785D01*
X470522Y-40863D01*
X426000D01*
X424800Y-42063D01*
Y-44463D01*
X426000Y-45663D01*
X470622D01*
X472700Y-47741D01*
Y-51385D01*
X470622Y-53463D01*
X424000D01*
X422800Y-54663D01*
Y-57063D01*
X424000Y-58263D01*
X468622D01*
X470700Y-60341D01*
Y-63985D01*
X468622Y-66063D01*
X424000D01*
X422800Y-67263D01*
Y-69663D01*
X424000Y-70863D01*
X468622D01*
X470700Y-72941D01*
Y-76585D01*
X468622Y-78663D01*
X424000D01*
X422800Y-79863D01*
Y-82263D01*
X424000Y-83463D01*
X468622D01*
X470700Y-85541D01*
Y-89185D01*
X468622Y-91263D01*
X424000D01*
X422800Y-92463D01*
Y-94863D01*
X424000Y-96063D01*
X444672D01*
X446750Y-98141D01*
Y-106200D01*
X447550Y-107000D01*
X451000D01*
G01X441000Y-18000D02*
X444450D01*
X445250Y-18800D01*
Y-25563D01*
X444050Y-26763D01*
X425478D01*
X423400Y-28841D01*
Y-32485D01*
X425478Y-34563D01*
X469900D01*
X471100Y-35763D01*
Y-38163D01*
X469900Y-39363D01*
X425378D01*
X423300Y-41441D01*
Y-45085D01*
X425378Y-47163D01*
X470000D01*
X471200Y-48363D01*
Y-50763D01*
X470000Y-51963D01*
X423378D01*
X421300Y-54041D01*
Y-57685D01*
X423378Y-59763D01*
X468000D01*
X469200Y-60963D01*
Y-63363D01*
X468000Y-64563D01*
X423378D01*
X421300Y-66641D01*
Y-70285D01*
X423378Y-72363D01*
X468000D01*
X469200Y-73563D01*
Y-75963D01*
X468000Y-77163D01*
X423378D01*
X421300Y-79241D01*
Y-82885D01*
X423378Y-84963D01*
X468000D01*
X469200Y-86163D01*
Y-88563D01*
X468000Y-89763D01*
X423378D01*
X421300Y-91841D01*
Y-95485D01*
X423378Y-97563D01*
X444050D01*
X445250Y-98763D01*
Y-106200D01*
X444450Y-107000D01*
X441000D01*
G54D114*
X238551Y373449D03*
Y369512D03*
Y365575D03*
Y381323D03*
Y377386D03*
X255165Y375417D03*
Y371481D03*
Y367543D03*
Y363606D03*
Y383292D03*
Y379355D03*
X303512Y373449D03*
Y369512D03*
Y365575D03*
Y381323D03*
Y377386D03*
X320126Y375417D03*
Y371481D03*
Y367543D03*
Y363606D03*
Y383292D03*
Y379355D03*
G54D21*
X18242Y259777D03*
X29947Y184247D03*
X44017Y38000D03*
X42103Y58317D03*
X44236Y187525D03*
X42403Y191535D03*
X37266Y184311D03*
X42501Y210701D03*
X48817Y264600D03*
X41421Y259638D03*
X36917Y317100D03*
X47017Y332000D03*
X35017Y338000D03*
X47017Y336000D03*
Y340000D03*
X38017Y348500D03*
Y352000D03*
X47017Y387700D03*
X47417Y397850D03*
Y401350D03*
X41517Y415700D03*
Y419700D03*
X34617Y411900D03*
Y415700D03*
X50733Y34873D03*
X51917Y220600D03*
X76517Y259200D03*
X90017Y255500D03*
X89767Y417000D03*
Y412500D03*
X104517Y80000D03*
X109818Y62963D03*
Y66963D03*
X123517Y114000D03*
Y131000D03*
X118817Y350300D03*
X126517Y54300D03*
X147593Y187354D03*
X152957Y242750D03*
X150617Y432600D03*
X155917Y158300D03*
X155617Y163400D03*
X156217Y167100D03*
X155717Y171000D03*
X154317Y195700D03*
X156874Y212568D03*
X155317Y301000D03*
Y297000D03*
Y305100D03*
X183017Y96000D03*
X177917Y272800D03*
X176017Y325200D03*
Y329200D03*
X174517Y432600D03*
X192317Y111300D03*
X194087Y260830D03*
X196617Y268700D03*
X183417Y300200D03*
Y304200D03*
X202517Y273000D03*
X214437Y97984D03*
X223017Y304600D03*
X223657Y372400D03*
X223647Y383260D03*
X229717Y258200D03*
X240521Y313514D03*
Y319310D03*
X246965Y257365D03*
X250330Y268403D03*
X247517Y313500D03*
Y322000D03*
X259017Y110300D03*
X258417Y259900D03*
X266978Y364610D03*
Y385343D03*
X270017Y399500D03*
X277267Y123250D03*
X300517Y57000D03*
X297517Y307000D03*
X288517Y372700D03*
X290242Y367508D03*
X289778Y391600D03*
X316117Y62700D03*
X308317Y134300D03*
X305398Y285092D03*
Y281088D03*
Y277100D03*
X305017Y311500D03*
X326144Y148439D03*
X330017Y358500D03*
Y376500D03*
Y367500D03*
Y372000D03*
Y363000D03*
Y381000D03*
Y385500D03*
X334317Y66000D03*
Y74000D03*
X334577Y125500D03*
X333817Y295900D03*
G54D123*
X377664Y18131D03*
Y387403D03*
X408750Y214188D03*
X398750Y412460D03*
G54D105*
X176953Y266800D03*
X171047D03*
X297821Y108055D03*
X291380Y106255D03*
X297821Y122106D03*
X291380Y120306D03*
X297821Y113961D03*
X291380Y112161D03*
X297821Y128012D03*
X291380Y126212D03*
X310661Y108055D03*
X304259Y106255D03*
Y120306D03*
X310661Y122106D03*
Y113961D03*
X304259Y112161D03*
Y126212D03*
X310661Y128012D03*
G54D12*
G01X130500Y74700D02*
X130532Y74732D01*
X131732D01*
X134244Y77244D01*
X136319D01*
X3000Y8494D03*
Y28494D03*
Y48494D03*
Y68494D03*
Y88494D03*
Y108494D03*
Y128494D03*
Y148494D03*
Y168494D03*
Y188494D03*
Y208494D03*
Y228494D03*
Y248494D03*
Y268494D03*
Y288494D03*
Y308494D03*
Y342126D03*
Y362126D03*
Y382126D03*
Y402126D03*
Y422126D03*
Y442126D03*
X9407Y10554D03*
X12900Y105500D03*
X19200Y102700D03*
X12500Y102000D03*
X16626Y195848D03*
X19129D03*
Y193048D03*
X16626D03*
X19100Y187420D03*
X19129Y204248D03*
X17000Y208017D03*
Y211541D03*
X16626Y198648D03*
Y201448D03*
X19129Y198648D03*
Y201448D03*
X16626Y204248D03*
X17000Y215713D03*
Y219288D03*
X15922Y224568D03*
Y227168D03*
X18422Y224568D03*
Y227168D03*
X18000Y240900D03*
Y237900D03*
Y249900D03*
Y246900D03*
Y243900D03*
X17065Y255712D03*
X15688Y259063D03*
X13736Y299891D03*
X6200Y312900D03*
X8300Y314700D03*
X13736Y303280D03*
X13827Y325310D03*
X13869Y352239D03*
X14000Y401700D03*
Y406700D03*
Y404200D03*
X17700Y427600D03*
X14600Y422500D03*
X14700Y425000D03*
X22218Y3000D03*
X27323Y25842D03*
X23723Y123791D03*
Y120791D03*
X32223Y123791D03*
Y120791D03*
X25200Y116300D03*
X31890Y110400D03*
X23736Y127758D03*
Y130758D03*
X32236Y127758D03*
Y130758D03*
X31920Y186610D03*
X21250Y206220D03*
X21000Y227000D03*
Y224500D03*
X21135Y236587D03*
X21205Y232767D03*
X21135Y240667D03*
Y243737D03*
X24690Y246467D03*
Y251967D03*
X21135Y246837D03*
X21035Y249937D03*
X24690Y249267D03*
X24705Y258767D03*
X22237Y304626D03*
X30638Y304602D03*
X22237Y301237D03*
X30638Y301213D03*
X22237Y311481D03*
Y308592D03*
X30638Y311957D03*
Y309068D03*
X30700Y315500D03*
X33000Y318700D03*
X25811Y319400D03*
X32000Y326300D03*
X23535Y329990D03*
X23810Y322534D03*
X31300Y329900D03*
X31000Y342500D03*
X34300Y375000D03*
X26300Y374400D03*
X36200Y368400D03*
X31600Y379600D03*
X33100Y392100D03*
X32700Y395381D03*
X20600Y428900D03*
X25202Y425329D03*
X29400Y430900D03*
X23677Y422419D03*
X31500Y428500D03*
X32100Y432800D03*
X20225Y447671D03*
X22692Y466518D03*
X42218Y3000D03*
X35044Y35751D03*
X45500Y41500D03*
X43926Y62248D03*
X35304Y58317D03*
X45500Y92500D03*
X45276Y98488D03*
X40340Y100710D03*
X45001Y95144D03*
X40723Y123791D03*
Y120791D03*
X49223Y123791D03*
Y121291D03*
X38300Y109200D03*
X48500Y112559D03*
X40940D03*
X40736Y127758D03*
Y130758D03*
X49236Y127758D03*
Y130758D03*
X47294Y184491D03*
X36599Y189016D03*
X37360Y194050D03*
X37823Y198346D03*
X48035Y191535D03*
X39408Y195990D03*
X47714Y212227D03*
X48940Y204871D03*
X47948Y201000D03*
X39900Y211000D03*
X39493Y222932D03*
X41993D03*
X44149Y227332D03*
X39493Y220332D03*
X41993D03*
X44149Y224732D03*
X48059Y214825D03*
X48023Y217860D03*
X39800Y213800D03*
X35700Y218000D03*
X39567Y243133D03*
X40500Y236900D03*
X35600Y241200D03*
Y238200D03*
X41574Y255937D03*
X51500Y258200D03*
X37485Y258807D03*
X41100Y248900D03*
X46220Y277170D03*
X47440Y304225D03*
X39039Y301299D03*
X47440Y301336D03*
Y308691D03*
X39039Y309044D03*
Y311933D03*
X47440Y312080D03*
X39039Y304278D03*
X50950Y318050D03*
X43500Y317100D03*
X48420Y321616D03*
X44200Y332000D03*
X44525Y324000D03*
X39100Y321600D03*
X44481Y328760D03*
X38560Y329739D03*
X35500Y340500D03*
Y335000D03*
X44220Y341008D03*
X44500Y344000D03*
Y355500D03*
X37400Y359900D03*
X44500Y348000D03*
X44525Y360000D03*
X35100Y352400D03*
X44500Y351600D03*
X38200Y364855D03*
X35900Y363025D03*
X37800Y371225D03*
X44525Y364000D03*
Y368000D03*
X37300Y375000D03*
X44525Y376000D03*
X37875Y377925D03*
X44525Y387800D03*
X37735Y391200D03*
X44525Y391650D03*
X35101Y381610D03*
X44525Y384000D03*
X37020Y385600D03*
X47075Y391730D03*
X44500Y380000D03*
X44490Y397850D03*
X44525Y394150D03*
X36911Y394915D03*
X37067Y398337D03*
X44341Y406480D03*
X44330Y401450D03*
X36600Y408600D03*
X39530Y409100D03*
X42900Y412900D03*
X46100Y412700D03*
X41200Y429100D03*
X43600Y422800D03*
X42200Y435900D03*
X38000Y428800D03*
X48050Y436350D03*
X45100Y435800D03*
X46100Y422800D03*
X40848Y448440D03*
X62218Y3000D03*
X54200Y25400D03*
X53000Y41500D03*
X58976Y36402D03*
X53600Y44100D03*
X56348Y36210D03*
X59425Y53075D03*
X50508Y57459D03*
X50710Y54724D03*
X57500Y75500D03*
X60000D03*
X55000Y76000D03*
X63086Y65762D03*
X52120Y78373D03*
X59240Y67242D03*
X52502Y80978D03*
X53434Y106562D03*
X53400Y102788D03*
X52155Y121218D03*
X60112Y113992D03*
X53267Y109094D03*
X59945Y117795D03*
Y120630D03*
X60411Y130200D03*
X52237Y129522D03*
X60800Y137000D03*
X61123Y133070D03*
X52876Y195712D03*
X52410Y186900D03*
X59700Y196200D03*
X52410Y190190D03*
X57141Y209341D03*
X59900Y199900D03*
X52050Y208760D03*
X64050Y201010D03*
X52948Y200700D03*
X58000Y217700D03*
X58823Y213531D03*
X52000Y230400D03*
X63300Y237600D03*
X51600Y241200D03*
X59850Y235830D03*
X51010Y233570D03*
X49700Y242900D03*
X50567Y238630D03*
X50700Y250400D03*
X62500Y272500D03*
X61200Y282600D03*
X58654Y290605D03*
X58900Y288075D03*
X54660Y311660D03*
X60561Y314843D03*
X60613Y312012D03*
X60600Y318000D03*
X64230Y303210D03*
X56600Y320500D03*
Y324300D03*
X52800Y322400D03*
X63000Y324100D03*
X56600Y318000D03*
X52820Y325200D03*
X60225Y336099D03*
X57400Y345400D03*
X52900Y360000D03*
X52600Y376600D03*
X58035Y370100D03*
X54400Y374700D03*
X55294Y369729D03*
X52475Y364000D03*
X52765Y390200D03*
X59500Y394000D03*
X58620Y408779D03*
X63200Y408600D03*
X52330Y413350D03*
X59097Y433502D03*
X57470Y426544D03*
X51535D03*
X59511Y424477D03*
X60622Y431273D03*
X64122D03*
X56250Y424200D03*
X52750D03*
X56482Y450344D03*
X62600Y450700D03*
X54100Y448600D03*
X56500Y447600D03*
X63563Y460100D03*
X56476D03*
X56482Y456844D03*
Y453344D03*
X63569Y456844D03*
Y453344D03*
X76500Y66500D03*
X65928Y76500D03*
X68500Y66500D03*
X75280Y75704D03*
X72500Y66500D03*
X74757Y89745D03*
Y92745D03*
Y86745D03*
Y83745D03*
X66830Y122329D03*
X66900Y125300D03*
X72044Y132312D03*
X71970Y135893D03*
X69195Y135799D03*
X69285Y132321D03*
X67126Y128100D03*
X66874Y130590D03*
X68335Y141369D03*
X68375Y144100D03*
X68434Y149506D03*
X68432Y152147D03*
X70580Y167179D03*
X72300Y159400D03*
X68600Y159160D03*
X76442Y166907D03*
X73550Y166680D03*
X67330Y169267D03*
X68960Y173300D03*
X75284Y180800D03*
X71124Y178565D03*
X65301Y187762D03*
X67486Y186414D03*
X75300Y183875D03*
X71146Y186489D03*
X71370Y188993D03*
X67386Y191935D03*
X67486Y188977D03*
X74046Y186490D03*
X71600Y200900D03*
X72150Y204810D03*
X76670Y208772D03*
X75000Y214000D03*
X72500D03*
X70453Y222900D03*
X74583Y217314D03*
X72000Y235925D03*
X70900Y241500D03*
X71100Y233575D03*
X67700Y229725D03*
X65801Y253145D03*
X68990Y257000D03*
X77010Y256645D03*
X65755Y256045D03*
X76200Y247400D03*
X73011Y246365D03*
X77384Y253769D03*
X68800Y253300D03*
X65800Y260875D03*
X76500Y270700D03*
X74000Y270800D03*
X68990Y260465D03*
X77437Y262760D03*
X76284Y280470D03*
X77900Y274700D03*
X70000Y280000D03*
X78600Y283970D03*
X75960Y284049D03*
X65100Y282475D03*
X72700Y301200D03*
X75870Y290700D03*
X78770Y290708D03*
X75300Y305150D03*
X69500Y308700D03*
X64567Y306665D03*
X73400Y313700D03*
X77500Y316100D03*
X73000Y323400D03*
X68500Y325100D03*
X81000Y321900D03*
X76900Y323000D03*
X76500Y325500D03*
X78700Y340000D03*
X78900Y336600D03*
X71700Y340600D03*
X71000Y394400D03*
X67900Y400525D03*
X79000Y395500D03*
X73976Y408665D03*
X69057Y419700D03*
X77860Y408678D03*
X77592Y413437D03*
X69139Y413452D03*
X66319Y413492D03*
X74782Y413800D03*
X67000Y408800D03*
X69700D03*
X78800Y423800D03*
X66297Y433002D03*
X71035Y426543D03*
X76770D03*
X69030Y422653D03*
X68100Y425400D03*
X71200Y431700D03*
X72150Y424199D03*
X75650D03*
X77600Y431400D03*
X79010Y445750D03*
X72800Y437900D03*
X70650Y460100D03*
X77500D03*
X82218Y3000D03*
X91700Y66500D03*
X86500Y75000D03*
X88000Y66500D03*
X84500D03*
X90151Y68985D03*
X91358Y89745D03*
Y92745D03*
Y86745D03*
Y83745D03*
X86700Y119100D03*
X92500Y116200D03*
X88500Y128000D03*
X89256Y135056D03*
X86100Y153340D03*
X89170Y141540D03*
X89200Y138800D03*
X86100Y155840D03*
X83410Y161020D03*
X86100Y158390D03*
X83520Y158520D03*
X81500Y176515D03*
X81800Y188500D03*
X80788Y190812D03*
X82370Y197010D03*
X90900Y222850D03*
X81600Y241500D03*
X87500Y237300D03*
X91300Y252900D03*
X80300Y243700D03*
X80270Y247830D03*
X84000Y261375D03*
X90800Y258225D03*
X83500Y266900D03*
X84016Y258230D03*
X91500Y267000D03*
X85672Y283985D03*
X92300Y282100D03*
X81864Y297900D03*
X85600Y298100D03*
X90923Y293520D03*
X82200Y308700D03*
X82022Y303350D03*
X84126Y311790D03*
X79600Y312000D03*
X85500Y323400D03*
Y326700D03*
X92698Y323224D03*
X93288Y330289D03*
X85600Y335000D03*
X81900Y337100D03*
X81700Y342600D03*
X86300Y397600D03*
X90500D03*
X82500D03*
X89487Y408435D03*
X87600Y414500D03*
X87800Y410300D03*
X84801Y409760D03*
X92500Y408630D03*
X86481Y407871D03*
X96030Y409400D03*
X81552Y409660D03*
X84320Y430510D03*
X93259Y424200D03*
X88565Y426535D03*
X79600Y426400D03*
X92001Y450402D03*
X82256Y445577D03*
X85276Y445550D03*
X81990Y448085D03*
X85490D03*
X92870Y437831D03*
X89700Y437900D03*
X84823Y460100D03*
X91909Y458275D03*
X92801Y452793D03*
X102218Y3000D03*
X107000Y44500D03*
X104575Y62369D03*
X102190Y63225D03*
X104600Y50501D03*
X104575Y67581D03*
X95400Y66500D03*
X98000Y75500D03*
X98500Y66500D03*
X102190Y66725D03*
X111000Y77000D03*
X104500Y73500D03*
X107124Y71004D03*
X108800Y91900D03*
X104425Y82500D03*
X110950Y82050D03*
X106000Y91900D03*
X108727Y99153D03*
X100000Y98500D03*
X111075Y104600D03*
X105916Y109952D03*
X100360Y116500D03*
X101230Y127010D03*
X96400Y137475D03*
X102999Y131799D03*
X108270Y138630D03*
X95950Y152900D03*
X95944Y149687D03*
X103500Y240619D03*
X98720Y236980D03*
X103580Y237400D03*
X106600Y253689D03*
X95300Y247100D03*
X97177Y263320D03*
X102600Y267000D03*
X107200Y265000D03*
X106800Y262076D03*
X97440Y283590D03*
X106574Y280028D03*
X106100Y282900D03*
X100700Y293600D03*
X108551Y294241D03*
X99990Y311200D03*
X105000Y311900D03*
X99990Y307900D03*
X105100Y309300D03*
X94400Y311100D03*
Y307200D03*
X100500Y328547D03*
X96457Y323194D03*
X105755Y327719D03*
X103000Y323800D03*
X95060Y327625D03*
X106852Y323292D03*
X97800Y325700D03*
X97608Y335534D03*
X99026Y338368D03*
X103180Y336286D03*
X108108Y395100D03*
X103400Y420000D03*
X95280Y412500D03*
X98100Y412400D03*
X105500Y418200D03*
X100457Y409100D03*
X108701Y418300D03*
X98300Y407600D03*
X108336Y411547D03*
X108500Y408680D03*
X109048Y425853D03*
X104112Y422946D03*
X103461Y425875D03*
X95845Y424755D03*
X97156Y450437D03*
X94560Y443287D03*
X100225Y443127D03*
X106700Y447730D03*
X95770Y437920D03*
X95870Y445483D03*
X99370D03*
X103900Y447640D03*
X98996Y458275D03*
X106083D03*
X96301Y452793D03*
X122218Y3000D03*
X111000Y44600D03*
X119000D03*
X115000Y44500D03*
X125800Y47330D03*
X122500Y58000D03*
X112800Y60400D03*
X112600Y52800D03*
X118500Y75500D03*
X116500Y74000D03*
X109121Y69500D03*
X119700Y89200D03*
X116560Y88651D03*
X123710Y82300D03*
X123740Y79791D03*
X115025Y104800D03*
X120726Y105000D03*
X115200Y98200D03*
X123325Y111000D03*
X120724Y108937D03*
X120626Y123500D03*
X112000D03*
X116200Y115100D03*
X109350Y115501D03*
X109200Y118500D03*
X120500Y115525D03*
X109200Y128500D03*
X118990Y131580D03*
X109670Y136060D03*
X118692Y137304D03*
X120800Y147200D03*
X117800D03*
X113000Y160700D03*
X115400Y159500D03*
X113000Y158000D03*
X122156Y157844D03*
X122900Y170100D03*
X123120Y213088D03*
X119060Y199695D03*
X123790Y227656D03*
X113590Y245170D03*
X118300Y237500D03*
X123690Y230156D03*
X122876Y242800D03*
X117840Y242200D03*
X112200Y234520D03*
X116143Y230790D03*
X112900Y239200D03*
X111400Y254680D03*
X122876Y245300D03*
X120020Y254430D03*
X119105Y251511D03*
X121720Y265330D03*
X117400Y266500D03*
X109800Y264928D03*
X111600Y262730D03*
X111100Y273700D03*
X111600Y284000D03*
X120070Y273700D03*
X115000D03*
X111177Y293471D03*
X122957Y300991D03*
X123100Y295974D03*
X120600Y293471D03*
X110565Y296331D03*
X118009Y313810D03*
Y311200D03*
X124935Y324900D03*
X115535Y335235D03*
X124300Y348800D03*
X115600Y337900D03*
X114700Y351200D03*
X121200Y359200D03*
X111330Y357800D03*
X120200Y361600D03*
X114700Y348500D03*
X111460Y361770D03*
X115000Y369500D03*
X111950Y371200D03*
X122047Y372260D03*
X125650Y368650D03*
X122330Y364670D03*
X111869Y365454D03*
X121175Y385125D03*
X119200Y389700D03*
X117410Y381350D03*
X110900Y378500D03*
X123100Y390600D03*
X119200Y406175D03*
X122600Y394600D03*
X119026Y393332D03*
X119791Y412301D03*
X112800Y421600D03*
X113000Y416200D03*
X116632Y411500D03*
X122498Y419675D03*
X112796Y412490D03*
X119500Y433600D03*
X111510Y434710D03*
X121700Y424005D03*
X123170Y433200D03*
X127900Y45000D03*
X129575Y57375D03*
X126425Y57000D03*
X133000Y59900D03*
X140730Y72600D03*
X130500Y74700D03*
X129300Y82650D03*
X131470Y81260D03*
X129500Y91475D03*
X129328Y122500D03*
X126575Y111416D03*
X131528Y114271D03*
X135500Y138000D03*
Y135000D03*
X134400Y127652D03*
X131700Y131000D03*
X132828Y138400D03*
X133500Y146800D03*
X138458Y146458D03*
X133500Y149385D03*
X124500Y167100D03*
X132500Y167300D03*
X126500Y158000D03*
X133690Y158100D03*
X136190D03*
X126300Y176575D03*
X126500Y174000D03*
X137900Y179160D03*
X135300Y175100D03*
X125700Y183700D03*
X135000Y206900D03*
X124338Y204742D03*
X124779Y201633D03*
X126153Y199079D03*
X135000Y221200D03*
X132500Y221900D03*
X138100Y213600D03*
X134891Y225171D03*
X124226Y225194D03*
X134358Y230069D03*
X130167Y234733D03*
X138000Y244600D03*
X128900Y255898D03*
X133000Y256100D03*
X128760Y265726D03*
X127600Y259700D03*
X131216Y280187D03*
X135315Y279813D03*
X125100Y273720D03*
X128760Y273701D03*
X137083Y278045D03*
X137196Y274491D03*
X132420Y273811D03*
X138600Y295900D03*
X124016Y313784D03*
X135462Y313727D03*
X124100Y311100D03*
X136100Y334000D03*
X129800Y325800D03*
X138590Y345710D03*
X124400Y345300D03*
X125910Y335006D03*
X125900Y337600D03*
X133300Y334100D03*
X136000Y341000D03*
X133100Y358900D03*
X133000Y361500D03*
X132600Y350090D03*
X124350Y352450D03*
X129776Y374500D03*
X138700Y376600D03*
X133640Y390524D03*
X126340Y382700D03*
X125174Y393916D03*
X124287Y406262D03*
X127300Y392600D03*
X135300Y399900D03*
X137900Y399500D03*
X131540Y394690D03*
X132700Y402700D03*
X129900Y415583D03*
X133500Y409110D03*
X129135Y410250D03*
X133070Y420874D03*
X134300Y416414D03*
X136230Y423935D03*
X128866Y433066D03*
X135350Y433016D03*
X124500Y424005D03*
X132070Y433110D03*
X133572Y423935D03*
X125930Y433110D03*
X138750Y451500D03*
X138500Y457250D03*
X138750Y454500D03*
X142218Y3000D03*
X147947Y9800D03*
X146800Y79000D03*
X152800Y75600D03*
X140869Y89055D03*
X145000Y90700D03*
X145100Y87400D03*
X142400Y91300D03*
X141100Y86500D03*
X141700Y96929D03*
X140869Y104803D03*
Y120551D03*
Y112677D03*
X148819Y123197D03*
X143400Y121700D03*
X141220Y123070D03*
X147600Y117000D03*
X151800Y116500D03*
X152800Y111600D03*
X148819Y125697D03*
X149800Y138100D03*
Y135100D03*
X145185Y134214D03*
X142892Y136645D03*
X142000Y146000D03*
X143269Y150456D03*
X150155Y145086D03*
X152556Y147683D03*
X148429Y147682D03*
X148400Y155765D03*
X144500Y169570D03*
X146300Y161010D03*
X153134Y178572D03*
X140554Y168887D03*
X153200Y170990D03*
X140554Y171688D03*
X146882Y177501D03*
X150619Y178646D03*
X145296Y188835D03*
X140830Y192530D03*
X153051Y187354D03*
X150005Y184973D03*
X149100Y189963D03*
X144280Y195130D03*
X151940Y203710D03*
X151900Y213200D03*
X143980Y199674D03*
X147800Y200789D03*
X140903Y199421D03*
X143742Y203395D03*
X152500Y199500D03*
X146390Y224040D03*
X146000Y216350D03*
X141954Y224274D03*
X142300Y216300D03*
X145500Y227700D03*
X142702Y227817D03*
X153100Y234800D03*
X149862Y243788D03*
X142085Y230549D03*
X151040Y237870D03*
X145250Y256890D03*
X145580Y248082D03*
X141280Y256310D03*
X142780Y266830D03*
X149215Y267745D03*
X152400Y284400D03*
X150240Y277940D03*
X152400Y293400D03*
X152500Y289425D03*
X150293Y302117D03*
X147500Y289405D03*
X141890Y310570D03*
X150293Y315493D03*
X151320Y322700D03*
X142500Y345800D03*
X148600Y336300D03*
X142202Y334000D03*
X142300Y336700D03*
X144800D03*
X144700Y334100D03*
X153419Y341978D03*
X143945Y354146D03*
X148316Y359086D03*
X141045Y355309D03*
X150900Y360325D03*
X151695Y357900D03*
X149500Y356700D03*
X141000Y358500D03*
X140700Y370252D03*
X145703Y370700D03*
X139200Y372510D03*
X149000Y383070D03*
X152100Y378400D03*
X152500Y382600D03*
X150820Y387325D03*
X143300Y396400D03*
X140300Y395100D03*
X141520Y399700D03*
X139400Y392460D03*
X151265Y399500D03*
X142511Y393690D03*
X146600Y410600D03*
X153079Y412000D03*
X149600Y410500D03*
X139700Y415100D03*
X150000Y414750D03*
X143000Y414600D03*
X140600Y412300D03*
X152100Y425700D03*
X145365Y426050D03*
X148060Y423500D03*
X148100Y433400D03*
X152200Y423100D03*
X148041Y426700D03*
X138987Y423935D03*
X151398Y449930D03*
X149041Y458750D03*
X162218Y3000D03*
X165700Y11100D03*
X166719Y75874D03*
X158246Y78872D03*
X156710Y73420D03*
X168297Y93976D03*
X164429Y93991D03*
X158873Y93976D03*
X166500Y96400D03*
X163423Y96281D03*
X159923D03*
X166200Y105500D03*
X158420Y116610D03*
X159700Y112000D03*
X155530Y116640D03*
X156286Y124903D03*
X156200Y111600D03*
X162657Y117297D03*
X154050Y137100D03*
X159000Y135000D03*
X166700Y132360D03*
X156406Y129203D03*
X162419Y131032D03*
X166733Y128700D03*
X155325Y139440D03*
X153954Y145086D03*
X161900Y150500D03*
X165690Y149622D03*
X159328Y160847D03*
X156481Y155933D03*
X162200Y158200D03*
X159900Y155600D03*
X161240Y177820D03*
X161237Y181735D03*
Y185815D03*
X161240Y190477D03*
X166361Y209794D03*
X156467Y203500D03*
X162594Y212585D03*
Y210085D03*
X166140Y205955D03*
X165381Y201274D03*
X166308Y225189D03*
X153744Y217435D03*
X153800Y214900D03*
X162653Y218843D03*
X159643Y226484D03*
X162200Y221376D03*
X167200Y222600D03*
X155800Y234700D03*
X161200Y233600D03*
X165500Y236100D03*
X157200Y240000D03*
X156970Y255000D03*
X165013Y254986D03*
X160973D03*
X164500Y266000D03*
X163690Y268610D03*
X160590Y263300D03*
X156970Y263250D03*
X164800Y263300D03*
X158750Y284949D03*
X168392Y298493D03*
X160850Y301344D03*
X168300Y301100D03*
X162100Y291600D03*
X161400Y307600D03*
X162160Y313560D03*
X170800Y317600D03*
X164500Y314800D03*
X155000Y321100D03*
X164790Y341100D03*
X168557Y341221D03*
X158459Y340898D03*
X158467Y344067D03*
X163800Y356800D03*
X161300Y354600D03*
X161154Y376704D03*
X156300Y376300D03*
X164318Y389102D03*
X157282D03*
X156900Y385700D03*
X154500Y387350D03*
X159050Y387334D03*
X162550D03*
X165500Y386000D03*
X165501Y382800D03*
X158200Y381400D03*
X155452Y401000D03*
X154000Y414750D03*
X160540Y416912D03*
X162100Y414000D03*
X165194Y428688D03*
X157294Y435623D03*
X156101Y425100D03*
X167008Y430718D03*
X165500Y433100D03*
X167865Y427771D03*
X163700Y422119D03*
X159396Y449408D03*
X160700Y445550D03*
X158100Y442700D03*
X160852Y460118D03*
X168029Y456660D03*
X157500Y453390D03*
X182218Y3000D03*
X176900Y14625D03*
X178200Y76145D03*
X175700Y76245D03*
X173853Y93991D03*
X182925Y84300D03*
X179900Y91300D03*
X181960Y99260D03*
X169700Y102250D03*
X176300Y98700D03*
X172847Y96281D03*
X169347D03*
X180333Y114292D03*
X179500Y116800D03*
X182000Y117200D03*
X171600Y114000D03*
X182865Y113706D03*
X174600Y114000D03*
X169100Y113900D03*
X182103Y132294D03*
X182108Y129094D03*
X170867Y128211D03*
X178290Y128824D03*
X174553Y128728D03*
X176550Y125210D03*
X178284Y132394D03*
X170610Y131900D03*
X174436Y132394D03*
X168800Y126800D03*
X172100Y146300D03*
X176000Y140500D03*
X172890Y153260D03*
X171700Y156900D03*
X169500Y180200D03*
X170800Y193100D03*
X172621Y208300D03*
X173800Y225400D03*
X170400Y214700D03*
X172400Y220700D03*
X175300Y240000D03*
X174400Y249136D03*
Y254736D03*
X179846Y255150D03*
X180458Y258825D03*
X174400Y251936D03*
X176900Y270100D03*
X174292Y263300D03*
X171592Y263312D03*
X168710Y272256D03*
X172977Y277000D03*
X182435Y281797D03*
X179217Y278528D03*
X168656Y275156D03*
X181194Y294074D03*
X182232Y296424D03*
X173880Y312430D03*
X174232Y304333D03*
X176563Y310917D03*
X176533Y314049D03*
X170550Y304050D03*
X169077Y308677D03*
X170561Y306631D03*
X182372Y325961D03*
X181050Y332250D03*
X171098Y341224D03*
X182700Y342216D03*
X169200Y349400D03*
X180600Y360200D03*
X180350Y368650D03*
X177500Y369100D03*
X177082Y387402D03*
X178850Y385634D03*
X182350D03*
X169669Y399419D03*
X172550Y398690D03*
X172530Y420950D03*
X182750Y426750D03*
X172530Y429470D03*
X184480Y429370D03*
X171400Y450600D03*
X193100Y69100D03*
X189400Y69600D03*
X187272Y84472D03*
X191312Y84512D03*
X190200Y100500D03*
X198281Y101286D03*
X184800Y100300D03*
X187700Y99000D03*
X187400Y101500D03*
X190800Y117200D03*
X193096Y115600D03*
X186891Y113991D03*
X190744Y114456D03*
X187069Y116800D03*
X184729Y115820D03*
X187360Y132425D03*
X187435Y129623D03*
X195983Y132294D03*
X191482Y129294D03*
X195983D03*
X186200Y125600D03*
X184000Y140500D03*
X196577Y141185D03*
X189700Y140400D03*
X196827Y240349D03*
X191693Y236370D03*
X185897Y249936D03*
X196240Y253430D03*
X193084Y257400D03*
X194567Y255288D03*
X187400Y255700D03*
X191583Y261363D03*
X190900Y271700D03*
X193386Y269142D03*
X184200Y264900D03*
X185000Y270700D03*
X189228Y280655D03*
X195370Y273297D03*
X183625Y273500D03*
X196200Y278200D03*
X196100Y281820D03*
X187623Y297475D03*
X196443Y294065D03*
X185725Y307320D03*
X192448Y308314D03*
X195031Y307182D03*
X194600Y313300D03*
X197853Y307200D03*
X197155Y314223D03*
X190465Y344426D03*
X190600Y337900D03*
X183800Y345400D03*
X197775Y346617D03*
X194800Y341700D03*
X191408Y357451D03*
X197450Y356560D03*
X190922Y350990D03*
X196050Y358770D03*
X191420Y354710D03*
X190965Y348090D03*
X197711Y349250D03*
X195000Y373900D03*
X187400Y379400D03*
X197400Y367600D03*
Y370250D03*
X184118Y387402D03*
X197620Y385425D03*
X187300Y384300D03*
X197660Y390870D03*
X190050Y389140D03*
X190100Y392270D03*
X191843Y403995D03*
X189054Y397500D03*
X194500Y402600D03*
X195800Y396780D03*
X185875Y415051D03*
X185245Y417500D03*
X190370Y422490D03*
X199940Y423700D03*
X197600Y415400D03*
X190270Y409962D03*
X189762Y429177D03*
X195300Y432327D03*
X189766Y432050D03*
X189838Y434910D03*
X186300Y448700D03*
X185000Y451500D03*
X189600Y459800D03*
X185000Y454000D03*
Y456500D03*
X191780Y453300D03*
Y456700D03*
X202218Y3000D03*
X207700Y59100D03*
X204300Y60600D03*
X201500Y61000D03*
X209142Y53664D03*
X213100Y69300D03*
X204100Y67400D03*
X209500Y92326D03*
X211800Y93870D03*
X201900Y83300D03*
X209824Y106122D03*
X203600Y117000D03*
X199940Y117500D03*
X211370Y117000D03*
X208200Y111760D03*
X203970Y125500D03*
X199985Y132294D03*
X212757Y127064D03*
X212727Y129654D03*
X208627Y132394D03*
X208576Y128957D03*
X204120Y132294D03*
X200000Y128764D03*
X208500Y126057D03*
X212727Y132154D03*
X211200Y140513D03*
X211490Y143700D03*
X205598Y140480D03*
X203542Y213254D03*
X206200Y255385D03*
X198990Y247811D03*
X200680Y257540D03*
X206051Y247911D03*
X211265Y267300D03*
X205500Y258300D03*
X201100Y265120D03*
X201000Y262500D03*
X203090Y269229D03*
X205590Y269129D03*
X205130Y282000D03*
X204258Y286691D03*
X213258Y273265D03*
X207220Y301180D03*
X204560Y301130D03*
X212911Y293869D03*
X206430Y298780D03*
X199729Y314565D03*
X198672Y318175D03*
X208628Y324665D03*
X200300Y328800D03*
X207750Y366500D03*
X208000Y373240D03*
X208360Y384890D03*
X208565Y404501D03*
X200222Y398150D03*
X213200Y399166D03*
X199880Y402846D03*
X203180Y416371D03*
X207539Y408686D03*
X200000Y407040D03*
X205223Y422665D03*
X207278Y416022D03*
X206150Y412821D03*
X198600Y426600D03*
X202513Y434800D03*
X198405D03*
X211865Y444520D03*
X199000Y444500D03*
X205200Y445400D03*
X213225Y442220D03*
X200000Y455800D03*
X209300Y457700D03*
X222218Y3000D03*
X214306Y62233D03*
X219600Y74000D03*
X215800Y69300D03*
X218600D03*
X224000Y74275D03*
X218600Y92100D03*
X221300D03*
X224330Y83210D03*
X224958Y107236D03*
X219900Y101300D03*
X216400Y106400D03*
X226040Y101220D03*
X222890Y101240D03*
X215294Y117094D03*
X226887Y117297D03*
X223300Y117400D03*
X221500Y125100D03*
X225284Y132294D03*
X229342Y129240D03*
X221278Y129294D03*
X225284D03*
X217262Y132294D03*
X221278D03*
X225300Y125200D03*
X227700Y151900D03*
X221000Y243000D03*
X220100Y237200D03*
X223800Y254800D03*
X227316Y256700D03*
X215100Y244100D03*
X215500Y247111D03*
X216800Y255550D03*
X215510Y253310D03*
X225275Y246000D03*
X217500Y264000D03*
X230196Y267477D03*
X219900Y267100D03*
X227232Y270539D03*
X222833Y261668D03*
X225441Y282267D03*
X219722Y286728D03*
X227841Y275773D03*
X219339Y284138D03*
X219359Y281580D03*
X226500Y273000D03*
X223672Y290735D03*
X223646Y293960D03*
X215600Y316800D03*
X213610Y308800D03*
X214400Y303997D03*
X216384Y312216D03*
X228800Y312100D03*
X226100Y325065D03*
X217300Y322800D03*
X225867Y345033D03*
X225650Y337520D03*
X221000Y343800D03*
X216405Y335970D03*
X214175Y333740D03*
X221000Y352000D03*
X223160Y362600D03*
X224632Y369825D03*
X225700Y362500D03*
X213490Y373690D03*
X226710Y364815D03*
X223420Y367080D03*
X220515Y384900D03*
X222575Y387625D03*
X227206Y400100D03*
X217390Y401340D03*
X222986Y400323D03*
X220134Y400780D03*
X222225Y407650D03*
X216725D03*
X219050Y418850D03*
X217725Y410150D03*
X221225D03*
X226830Y435170D03*
X225000Y433100D03*
X219250Y422150D03*
X213900Y436000D03*
X217100Y436100D03*
X218085Y444520D03*
X224000Y449100D03*
X216725Y442220D03*
X222200Y458700D03*
X215000Y458600D03*
X242218Y3000D03*
X233000Y47100D03*
X237000Y47200D03*
X230800Y57613D03*
X234537Y74638D03*
X240000Y67400D03*
X239347Y79457D03*
X230600Y91700D03*
X239660Y91920D03*
X232150Y82480D03*
X235630Y104990D03*
X231592Y110500D03*
X237280Y107510D03*
X229000Y101000D03*
X240160Y107000D03*
X240710Y99570D03*
X232325Y101230D03*
X236648Y100739D03*
X242812Y117501D03*
X238900Y114800D03*
X234500Y117500D03*
X230293Y117417D03*
X239900Y117550D03*
X239206Y112300D03*
X242800Y132200D03*
X231100Y125600D03*
X233511Y132594D03*
X234900Y126100D03*
X229396Y132294D03*
X242500Y129000D03*
X242195Y141003D03*
X232384Y148884D03*
X230535Y244564D03*
X237700Y257387D03*
X237730Y248085D03*
X242690Y255300D03*
X230000Y255700D03*
X232773Y269532D03*
X232300Y261200D03*
X239298Y268800D03*
X242940Y268500D03*
X233033Y266483D03*
X229630Y264404D03*
X242087Y271427D03*
X238531Y263081D03*
X231900Y272700D03*
X241188Y279347D03*
X241263Y282654D03*
X242700Y306800D03*
X228800Y302700D03*
X240500Y316575D03*
X236688Y311217D03*
X238400Y304200D03*
X228800Y305500D03*
X235400Y303800D03*
X241400Y328100D03*
X242592Y330683D03*
X243010Y323400D03*
X230445Y325945D03*
X233468Y341046D03*
X235000Y335300D03*
X231689Y334896D03*
X233500Y346911D03*
Y343911D03*
X233300Y356890D03*
X231500Y352500D03*
X233650Y359628D03*
X233800Y354300D03*
X233600Y371500D03*
X230287Y373100D03*
X233800Y390118D03*
X228230Y390390D03*
X232470Y382280D03*
X233600Y377300D03*
X233790Y384490D03*
X239750Y394970D03*
X236670Y394550D03*
X236860Y407300D03*
X229900Y436600D03*
X236900Y440565D03*
X239500Y447750D03*
X235400Y451600D03*
X231250Y447000D03*
X235200Y449100D03*
X231400Y449500D03*
X241436Y445784D03*
X240200Y450650D03*
X228200Y459100D03*
X236221Y454400D03*
X240010Y456000D03*
X240210Y453400D03*
X231400Y452000D03*
X248359Y46559D03*
X252925Y54000D03*
X249475Y55812D03*
X256000Y56000D03*
X248700Y75900D03*
X255750Y77350D03*
X246200Y74600D03*
X253000Y77500D03*
X250000Y73000D03*
X250900Y90900D03*
X255000Y82700D03*
X257800Y82800D03*
X256900Y87300D03*
X251200Y93800D03*
X254397Y103697D03*
X244987Y103528D03*
X251113Y102919D03*
X252300Y107664D03*
X245391Y99589D03*
X251900Y100100D03*
X255213Y106099D03*
X249988Y105792D03*
X246488D03*
X244208Y97302D03*
X247200Y117400D03*
X253100Y119900D03*
X245310Y113910D03*
X252374Y132159D03*
X245500Y127800D03*
X245520Y130600D03*
X258500Y146400D03*
X251354Y152877D03*
X249300Y237600D03*
X247689Y247929D03*
X253110Y254909D03*
X253100Y257800D03*
X252639Y247885D03*
X256700Y263800D03*
X255700Y260000D03*
X247470Y269990D03*
X253388Y273655D03*
X250288Y273581D03*
X251459Y286542D03*
Y283542D03*
X246200Y299700D03*
X246514Y294325D03*
Y296825D03*
X258100Y295080D03*
X254355Y300577D03*
X247923Y316400D03*
X245900Y305000D03*
X248900Y304900D03*
X247923Y319000D03*
X253320Y323327D03*
X256124Y336355D03*
X243750Y369730D03*
X243700Y372730D03*
X244790Y375910D03*
X243410Y381323D03*
X248800Y385700D03*
X252350Y412850D03*
X257810Y435100D03*
X245300Y445800D03*
X246700Y451500D03*
X246500Y448500D03*
X243375Y448375D03*
X246700Y454100D03*
X262218Y3000D03*
X267022Y12166D03*
X269095Y34625D03*
X260970Y42441D03*
X259000Y47500D03*
X267939Y41122D03*
X268500Y45500D03*
X268675Y74400D03*
X267168Y93768D03*
X260132D03*
X259894Y90072D03*
X263102Y91725D03*
X272505Y83545D03*
X260050Y87026D03*
X259759Y103651D03*
X259500Y101100D03*
X265801Y106040D03*
X260970Y98600D03*
X258713Y106099D03*
X268435Y121476D03*
X271602Y121400D03*
X269561Y130987D03*
X271300Y132900D03*
X269493Y138604D03*
X260200Y132395D03*
X260388Y125001D03*
X263294Y153366D03*
X263030Y150846D03*
X268442Y153299D03*
X265942D03*
Y150799D03*
X268442D03*
X269004Y144450D03*
Y141950D03*
X269133Y164982D03*
X265226D03*
X268339Y222126D03*
X272300Y251000D03*
X258628Y247600D03*
X258475Y254872D03*
X267100Y265000D03*
X269016Y266991D03*
X259500Y263700D03*
X262730Y267600D03*
X258000Y266300D03*
X266600Y268700D03*
X262700Y265100D03*
X258000Y284900D03*
X266200Y300500D03*
X266250Y297900D03*
X266200Y294800D03*
X261500Y290440D03*
X266300Y307500D03*
X262310Y311225D03*
X264265Y315817D03*
X262930Y325300D03*
X261300Y334100D03*
X259420Y345930D03*
X271100Y346575D03*
X259420Y343230D03*
Y340630D03*
X265922Y354238D03*
X271990Y362360D03*
X272100Y396300D03*
X265320Y392290D03*
X274190Y408900D03*
X265100Y395100D03*
X272400Y392400D03*
X269700Y411379D03*
X271500Y418300D03*
X265100Y424000D03*
X266300Y435900D03*
X267100Y432900D03*
X263800Y430300D03*
X272999Y430500D03*
X271500Y446800D03*
X271710Y449840D03*
X266727Y443185D03*
X261700Y439700D03*
X265130Y440070D03*
X261100Y443500D03*
X269534Y459061D03*
X269561Y456044D03*
X282218Y3000D03*
X277000Y41982D03*
X286000Y47000D03*
X282440Y51941D03*
X274219Y51641D03*
X277000Y51665D03*
X274500Y58000D03*
X279934Y51688D03*
X286000Y67975D03*
X279800Y72700D03*
X274400Y90019D03*
X290000Y82000D03*
X273400Y92800D03*
X276400Y92300D03*
X287578Y84092D03*
X283500Y89500D03*
X277505Y83545D03*
X282505D03*
X278300Y95019D03*
X274760Y105140D03*
X275386Y102710D03*
X280910Y102880D03*
X279200Y114100D03*
X288116Y120306D03*
X285250Y117250D03*
X274200Y109500D03*
X280400Y126000D03*
X274500Y131629D03*
X279600Y131400D03*
X283500Y126000D03*
X275960Y126010D03*
X273450Y125050D03*
X287796Y131542D03*
X288280Y126212D03*
X280744Y142070D03*
X283248Y142046D03*
X280616Y150971D03*
X283616D03*
X287555Y142419D03*
X285899Y153542D03*
X283399D03*
X278155Y176085D03*
X279457Y171318D03*
X286000Y242100D03*
X279983Y235254D03*
X282483D03*
X283974Y251372D03*
X286800Y251400D03*
X276200Y251500D03*
X280082Y251328D03*
X280030Y267098D03*
Y264098D03*
X284357Y267027D03*
Y264027D03*
X285911Y269899D03*
X281889D03*
X287755Y287538D03*
X282911Y279569D03*
X287507Y301596D03*
X281300Y308800D03*
X287050Y305850D03*
X289939Y309060D03*
X276660Y316900D03*
X276155Y329999D03*
X273355Y330001D03*
X289600Y322253D03*
X286372Y326768D03*
X285860Y336131D03*
X277500Y348469D03*
X275520Y357910D03*
X277290Y355820D03*
X277572Y351198D03*
X276100Y375900D03*
X287725Y363473D03*
X287761Y366200D03*
X287500Y376900D03*
X276145Y366455D03*
X276100Y381500D03*
X284614Y387136D03*
X283664Y379236D03*
X273100Y381500D03*
X283973Y382553D03*
X285191Y390840D03*
X287630Y389378D03*
X275700Y403500D03*
X277700Y406100D03*
X287476Y396680D03*
X281300Y419300D03*
X278200Y408700D03*
X278900Y421400D03*
X281300Y416200D03*
X277700Y412580D03*
X287500Y416100D03*
X278409Y433722D03*
X276400Y431810D03*
X275100Y427682D03*
X274619Y424725D03*
X283622Y447155D03*
X275138Y451215D03*
X276632Y439502D03*
X283674Y449975D03*
X277563Y460028D03*
X283707Y459398D03*
X283715Y452769D03*
X302218Y3000D03*
X300600Y10591D03*
X288856Y12166D03*
X295402Y48051D03*
X290245Y46978D03*
X297466Y51521D03*
X300425Y54516D03*
X290000Y67975D03*
X297575Y73738D03*
X300070Y84000D03*
X300856Y104059D03*
X301151Y108649D03*
X294600Y106900D03*
X304000Y116500D03*
X294800Y111800D03*
X298975Y118900D03*
X301000Y121016D03*
X300500Y125000D03*
X295075Y119100D03*
X301936Y135797D03*
X294200Y128800D03*
X301000Y129900D03*
X290200Y129500D03*
X293693Y152232D03*
X290889Y152318D03*
X298005Y151118D03*
Y148618D03*
Y146118D03*
X292204Y142610D03*
X301936Y143897D03*
X301507Y195435D03*
X301120Y226421D03*
X296734Y216079D03*
X301120Y229810D03*
X290586Y234844D03*
X288086D03*
X301120Y235626D03*
Y238765D03*
X299138Y244513D03*
X302687Y275497D03*
X291500Y287670D03*
Y285170D03*
X298840Y279640D03*
X291000Y297700D03*
X291300Y315900D03*
X296938Y325700D03*
X301500Y326500D03*
X290000Y335600D03*
X300700Y341300D03*
X295500Y354920D03*
X296780Y371500D03*
X298748Y390118D03*
X298152Y393332D03*
X297399Y397382D03*
X292700Y403700D03*
X290800Y438300D03*
X291623Y447747D03*
X291703Y450819D03*
X291689Y453912D03*
Y456912D03*
Y459912D03*
X295729Y453912D03*
Y456912D03*
Y459912D03*
X297738Y452418D03*
Y458418D03*
Y455418D03*
X313977Y33400D03*
X303575Y54516D03*
X316025Y60200D03*
X309570Y84000D03*
X316066Y108407D03*
X315100Y116400D03*
X307400Y122300D03*
X304436Y135897D03*
X307500Y125635D03*
X315900Y125900D03*
X313800Y124300D03*
X307560Y128500D03*
X305936Y143897D03*
X309936D03*
X313936D03*
X309521Y226397D03*
X307487Y219503D03*
X304987D03*
X310449Y218617D03*
X317110Y219140D03*
X309521Y229786D03*
Y235352D03*
Y238741D03*
X307500Y256500D03*
X305000Y252400D03*
X307600Y252300D03*
X307800Y259200D03*
X312114Y288439D03*
X312272Y282107D03*
X302800Y286200D03*
X311670Y285160D03*
X302879Y282487D03*
Y279686D03*
X309700Y294789D03*
X315810Y293450D03*
X312315Y293207D03*
X317430Y295665D03*
X314820Y296128D03*
X314201Y302361D03*
X314180Y299440D03*
X303077Y297519D03*
X306500Y301500D03*
X314132Y310178D03*
X314170Y307020D03*
X309500Y315000D03*
X304000Y305000D03*
X303000Y309200D03*
X306200Y308800D03*
X311000Y320500D03*
X315075Y366500D03*
X308906Y362637D03*
X314340Y373296D03*
X311925Y366475D03*
X312226Y382766D03*
X308500Y382100D03*
X314985Y397639D03*
Y394639D03*
X308926Y401900D03*
X314969Y456527D03*
X322218Y3000D03*
X319175Y60200D03*
X321800Y60055D03*
X322600Y76100D03*
X331881Y108593D03*
Y104577D03*
X320500Y100400D03*
X331881Y112608D03*
X324011Y118843D03*
X324023Y121943D03*
Y115643D03*
X320765Y114582D03*
X320938Y122677D03*
X318000Y117200D03*
X329297Y134594D03*
Y129890D03*
X321276Y134532D03*
X321349Y130044D03*
X331741Y138243D03*
Y125796D03*
X320239Y151075D03*
X317936Y143897D03*
X323509Y153377D03*
X329005Y152657D03*
X328087Y141608D03*
X331641Y141743D03*
X321600Y142100D03*
X323384Y157378D03*
X331405Y157411D03*
X323384Y165378D03*
Y161378D03*
X331405Y164911D03*
Y159911D03*
Y154911D03*
Y167411D03*
X323384Y169378D03*
Y173378D03*
Y177378D03*
X331405Y177411D03*
Y179911D03*
Y174911D03*
Y169911D03*
Y182926D03*
Y172411D03*
Y187411D03*
Y192411D03*
Y189911D03*
X320054Y195163D03*
X319601Y201140D03*
X326932Y205685D03*
X326733Y209885D03*
X321045Y210257D03*
X320937Y212839D03*
X326733Y201485D03*
X320054Y198663D03*
X326323Y226349D03*
X317922Y226373D03*
X326731Y213648D03*
X320931Y215387D03*
X326323Y229738D03*
X317922Y229762D03*
Y238717D03*
Y235328D03*
X326323Y235304D03*
Y238693D03*
X327162Y278972D03*
X317670Y291430D03*
X330900Y314700D03*
X325007Y328608D03*
Y326008D03*
X327704Y328635D03*
Y326035D03*
X325007Y323508D03*
X327704Y323535D03*
X325038Y356890D03*
X329925Y356016D03*
X325900Y365643D03*
X326100Y375717D03*
X326200Y370681D03*
X325320Y390118D03*
X325200Y383900D03*
X331500Y383300D03*
X326375Y380724D03*
X332470Y397092D03*
Y394092D03*
X325593Y406500D03*
X329093D03*
X318593D03*
X322093D03*
X331646Y466536D03*
X342218Y3000D03*
X337375Y76600D03*
X342900Y66100D03*
X339900Y69100D03*
Y66000D03*
X339908Y104577D03*
Y108593D03*
X342200Y100500D03*
X342180Y106900D03*
X339101Y117328D03*
Y121128D03*
X339908Y112609D03*
X337842Y128533D03*
X333278Y151129D03*
X339369Y151952D03*
X339800Y154911D03*
Y159911D03*
Y165911D03*
X339939Y162911D03*
X339800Y169911D03*
Y176911D03*
Y179911D03*
X339812Y173380D03*
X339800Y182926D03*
Y185911D03*
Y189911D03*
X337083Y197000D03*
X337400Y193449D03*
X337004Y206113D03*
X334723Y226349D03*
Y229738D03*
X334724Y238669D03*
Y235280D03*
X337467Y236984D03*
X336312Y286352D03*
X336461Y283202D03*
X340612Y278972D03*
X339700Y295900D03*
Y293000D03*
X347100Y313700D03*
X342604Y318773D03*
X345500Y342690D03*
X335475Y358500D03*
X335700Y376400D03*
X335500Y363200D03*
X335475Y367500D03*
X335708Y372008D03*
X334600Y383300D03*
X335500Y380000D03*
X334112Y447668D03*
X351331Y20788D03*
Y40788D03*
Y60788D03*
Y80788D03*
Y100788D03*
Y120788D03*
Y140788D03*
Y160788D03*
Y180788D03*
Y200788D03*
Y220788D03*
Y240788D03*
Y260788D03*
Y280788D03*
Y300788D03*
X349290Y337646D03*
X351331Y357531D03*
Y377531D03*
Y397531D03*
Y417531D03*
Y437531D03*
X373420Y-447134D03*
X370905D03*
Y-443881D03*
X373420D03*
X376346Y-447134D03*
X375904Y-438145D03*
X374975Y-435380D03*
X372211Y-440841D03*
X375964Y-215959D03*
X374666Y-218571D03*
X373480Y-210223D03*
X370965D03*
Y-206970D03*
X376406Y-206985D03*
X373480Y-206970D03*
X372271Y-213263D03*
X375876Y-159873D03*
X372183Y-162569D03*
X373392Y-168862D03*
X370877D03*
Y-165609D03*
X373392D03*
X376318Y-168862D03*
X374947Y-157108D03*
X375964Y12313D03*
X374666Y9701D03*
X373480Y18049D03*
X370965D03*
X372271Y15009D03*
X370965Y21302D03*
X376406Y21287D03*
X373480Y21302D03*
X373420Y59410D03*
X370905D03*
Y62663D03*
X373420D03*
X376346Y59410D03*
X375904Y68399D03*
X374975Y71164D03*
X372211Y65703D03*
X375964Y381585D03*
X374666Y378973D03*
X372271Y384281D03*
X376406Y390559D03*
X373480Y387321D03*
Y390574D03*
X370965Y387321D03*
Y390574D03*
X391993Y-473196D03*
Y-469943D03*
X381788Y-443881D03*
X384303D03*
Y-447134D03*
X378862Y-447119D03*
X381788Y-447134D03*
X379304Y-438145D03*
X380602Y-435533D03*
X382997Y-440841D03*
X379364Y-215959D03*
X380293Y-218724D03*
X383057Y-213263D03*
X381848Y-206970D03*
X384363D03*
Y-210223D03*
X381848D03*
X378922Y-206970D03*
X379276Y-159873D03*
X381760Y-165609D03*
X384275D03*
Y-168862D03*
X378834Y-168847D03*
X381760Y-168862D03*
X382969Y-162569D03*
X380574Y-157261D03*
X392081Y-115285D03*
Y-112032D03*
X391950Y-74043D03*
Y-70790D03*
X379364Y12313D03*
X380293Y9548D03*
X383057Y15009D03*
X384363Y18049D03*
X381848D03*
Y21302D03*
X384363D03*
X378922D03*
X381788Y62663D03*
X384303D03*
Y59410D03*
X378862Y59425D03*
X381788Y59410D03*
X379304Y68399D03*
X380602Y71011D03*
X382997Y65703D03*
X391950Y214106D03*
Y217359D03*
Y255229D03*
Y258482D03*
X379364Y381585D03*
X380293Y378820D03*
X378922Y390574D03*
X381848D03*
Y387321D03*
X384363Y390574D03*
Y387321D03*
X383057Y384281D03*
X391950Y412378D03*
Y415631D03*
X405391Y-473196D03*
X399950Y-473181D03*
X402876Y-473196D03*
X394508D03*
X397434D03*
X396992Y-464207D03*
X400392D03*
X396063Y-461442D03*
X401690Y-461595D03*
X402876Y-469943D03*
X405391D03*
X404085Y-466903D03*
X393299D03*
X394508Y-469943D03*
X397080Y-121021D03*
X400480D03*
X401409Y-123786D03*
X395782Y-123633D03*
X394596Y-115285D03*
X393387Y-118325D03*
X404173D03*
X405479Y-115285D03*
X402964D03*
X397522Y-112047D03*
X394596Y-112032D03*
X402964D03*
X405479D03*
X400038D03*
X399450Y-74028D03*
X394450Y-74043D03*
Y-70790D03*
X396950Y-74043D03*
X405050D03*
X402550D03*
X405050Y-70790D03*
X402550D03*
X393357Y-67750D03*
X403643D03*
X393357Y211066D03*
X403857D03*
X394450Y217359D03*
Y214106D03*
X396950Y217359D03*
X399450Y217344D03*
X402450Y217359D03*
X404950D03*
X402450Y214106D03*
X404950D03*
X394450Y255229D03*
X396950D03*
X399450Y255244D03*
X405050Y255229D03*
X402550D03*
X394450Y258482D03*
X393357Y261522D03*
X405050Y258482D03*
X402550D03*
X403643Y261522D03*
X394450Y415631D03*
Y412378D03*
X396950Y415631D03*
X399450Y415616D03*
X393357Y409338D03*
X402450Y415631D03*
X404950D03*
X402450Y412378D03*
X404950D03*
X403857Y409338D03*
X415550Y-70790D03*
Y-74043D03*
X413050D03*
Y-70790D03*
X410550Y-74043D03*
X408050Y-74028D03*
X414143Y-67750D03*
Y211066D03*
X415550Y214106D03*
Y217359D03*
X413050D03*
Y214106D03*
X410550Y217359D03*
X408050Y217344D03*
X415550Y255229D03*
X413050D03*
X410550D03*
X408050Y255244D03*
X415550Y258482D03*
X413050D03*
X414143Y261522D03*
X415550Y412378D03*
Y415631D03*
X413050D03*
Y412378D03*
X410550Y415631D03*
X408050Y415616D03*
X414143Y409338D03*
G54D30*
X22282Y197854D03*
G54D133*
G01X2010999Y-388000D02*
Y1475775D01*
X-407000D01*
Y-386798D01*
Y-755294D01*
Y-793716D01*
X-368578D01*
X1942346D01*
X2010999D01*
Y-725063D01*
Y-388000D01*
G01X-53307Y-609436D02*
Y-684436D01*
X446693D01*
Y-609436D01*
X-53307D01*
G01X-41307Y-674436D02*
Y-679436D01*
G01X-42764Y-674436D02*
X-39850D01*
G01X-34940Y-679436D02*
X-37474D01*
Y-674436D01*
X-34940D01*
G01X-35954Y-676853D02*
X-37474D01*
G01X-32374Y-674436D02*
Y-679436D01*
X-29840D01*
G01X-26007Y-679603D02*
X-26134Y-679519D01*
Y-679353D01*
X-26007Y-679269D01*
X-25880Y-679353D01*
Y-679519D01*
X-26007Y-679603D01*
G01Y-677353D02*
X-26134Y-677269D01*
Y-677103D01*
X-26007Y-677019D01*
X-25880Y-677103D01*
Y-677269D01*
X-26007Y-677353D01*
G01X-21224Y-681103D02*
X-21857Y-680269D01*
X-22174Y-679436D01*
Y-676103D01*
X-21857Y-675269D01*
X-21224Y-674436D01*
G01X-15807D02*
X-16314Y-674603D01*
X-16694Y-675019D01*
X-16947Y-675519D01*
X-17137Y-676186D01*
X-17200Y-676936D01*
X-17137Y-677686D01*
X-16947Y-678353D01*
X-16694Y-678853D01*
X-16314Y-679269D01*
X-15807Y-679436D01*
X-15300Y-679269D01*
X-14920Y-678853D01*
X-14667Y-678353D01*
X-14477Y-677686D01*
X-14414Y-676936D01*
X-14477Y-676186D01*
X-14667Y-675519D01*
X-14920Y-675019D01*
X-15300Y-674603D01*
X-15807Y-674436D01*
G01X-12100Y-678436D02*
X-11720Y-679019D01*
X-11214Y-679353D01*
X-10644Y-679436D01*
X-10137Y-679353D01*
X-9630Y-678936D01*
X-9314Y-678436D01*
X-9250Y-677936D01*
X-9377Y-677353D01*
X-9820Y-676936D01*
X-10264Y-676769D01*
X-10834D01*
G01X-10264D02*
X-9884Y-676519D01*
X-9567Y-676103D01*
X-9440Y-675603D01*
X-9567Y-675103D01*
X-9884Y-674686D01*
X-10454Y-674436D01*
X-11024Y-674519D01*
X-11594Y-674853D01*
G01X-5290Y-681103D02*
X-4657Y-680269D01*
X-4340Y-679436D01*
Y-676103D01*
X-4657Y-675269D01*
X-5290Y-674436D01*
G01X-1900Y-678436D02*
X-1520Y-679019D01*
X-1014Y-679353D01*
X-444Y-679436D01*
X63Y-679353D01*
X570Y-678936D01*
X886Y-678436D01*
X950Y-677936D01*
X823Y-677353D01*
X380Y-676936D01*
X-64Y-676769D01*
X-634D01*
G01X-64D02*
X316Y-676519D01*
X633Y-676103D01*
X760Y-675603D01*
X633Y-675103D01*
X316Y-674686D01*
X-254Y-674436D01*
X-824Y-674519D01*
X-1394Y-674853D01*
G01X3390Y-675269D02*
X3770Y-674769D01*
X4213Y-674519D01*
X4720Y-674436D01*
X5353Y-674603D01*
X5796Y-675019D01*
X5923Y-675519D01*
X5860Y-676019D01*
X5606Y-676436D01*
X4340Y-677269D01*
X3770Y-677853D01*
X3390Y-678686D01*
X3263Y-679436D01*
X5923D01*
G01X9566D02*
X9693Y-678353D01*
X9883Y-677436D01*
X10136Y-676603D01*
X10453Y-675686D01*
X10960Y-674436D01*
X8426D01*
G01X13970Y-677769D02*
X15616D01*
G01X18690Y-675269D02*
X19070Y-674769D01*
X19513Y-674519D01*
X20020Y-674436D01*
X20653Y-674603D01*
X21096Y-675019D01*
X21223Y-675519D01*
X21160Y-676019D01*
X20906Y-676436D01*
X19640Y-677269D01*
X19070Y-677853D01*
X18690Y-678686D01*
X18563Y-679436D01*
X21223D01*
G01X23600Y-678436D02*
X23980Y-679019D01*
X24486Y-679353D01*
X25056Y-679436D01*
X25563Y-679353D01*
X26070Y-678936D01*
X26386Y-678436D01*
X26450Y-677936D01*
X26323Y-677353D01*
X25880Y-676936D01*
X25436Y-676769D01*
X24866D01*
G01X25436D02*
X25816Y-676519D01*
X26133Y-676103D01*
X26260Y-675603D01*
X26133Y-675103D01*
X25816Y-674686D01*
X25246Y-674436D01*
X24676Y-674519D01*
X24106Y-674853D01*
G01X30853Y-679436D02*
Y-674436D01*
X28510Y-678019D01*
X31676D01*
G01X33800Y-678686D02*
X34180Y-679103D01*
X34623Y-679353D01*
X35193Y-679436D01*
X35763Y-679269D01*
X36206Y-678936D01*
X36523Y-678353D01*
X36586Y-677686D01*
X36460Y-677019D01*
X36143Y-676603D01*
X35700Y-676269D01*
X35256Y-676186D01*
X34813Y-676269D01*
X34243Y-676603D01*
X34433Y-674436D01*
X36143D01*
G01X44190Y-679436D02*
Y-674436D01*
X46596D01*
G01X45710Y-676853D02*
X44190D01*
G01X48910Y-679436D02*
X50493Y-674436D01*
X52076Y-679436D01*
G01X51506Y-677686D02*
X49480D01*
G01X54263Y-679436D02*
X56923Y-674436D01*
G01X54263D02*
X56923Y-679436D01*
G01X60693Y-679603D02*
X60566Y-679519D01*
Y-679353D01*
X60693Y-679269D01*
X60820Y-679353D01*
Y-679519D01*
X60693Y-679603D01*
G01Y-677353D02*
X60566Y-677269D01*
Y-677103D01*
X60693Y-677019D01*
X60820Y-677103D01*
Y-677269D01*
X60693Y-677353D01*
G01X65476Y-681103D02*
X64843Y-680269D01*
X64526Y-679436D01*
Y-676103D01*
X64843Y-675269D01*
X65476Y-674436D01*
G01X70893D02*
X70386Y-674603D01*
X70006Y-675019D01*
X69753Y-675519D01*
X69563Y-676186D01*
X69500Y-676936D01*
X69563Y-677686D01*
X69753Y-678353D01*
X70006Y-678853D01*
X70386Y-679269D01*
X70893Y-679436D01*
X71400Y-679269D01*
X71780Y-678853D01*
X72033Y-678353D01*
X72223Y-677686D01*
X72286Y-676936D01*
X72223Y-676186D01*
X72033Y-675519D01*
X71780Y-675019D01*
X71400Y-674603D01*
X70893Y-674436D01*
G01X74600Y-678436D02*
X74980Y-679019D01*
X75486Y-679353D01*
X76056Y-679436D01*
X76563Y-679353D01*
X77070Y-678936D01*
X77386Y-678436D01*
X77450Y-677936D01*
X77323Y-677353D01*
X76880Y-676936D01*
X76436Y-676769D01*
X75866D01*
G01X76436D02*
X76816Y-676519D01*
X77133Y-676103D01*
X77260Y-675603D01*
X77133Y-675103D01*
X76816Y-674686D01*
X76246Y-674436D01*
X75676Y-674519D01*
X75106Y-674853D01*
G01X81410Y-681103D02*
X82043Y-680269D01*
X82360Y-679436D01*
Y-676103D01*
X82043Y-675269D01*
X81410Y-674436D01*
G01X84800Y-678436D02*
X85180Y-679019D01*
X85686Y-679353D01*
X86256Y-679436D01*
X86763Y-679353D01*
X87270Y-678936D01*
X87586Y-678436D01*
X87650Y-677936D01*
X87523Y-677353D01*
X87080Y-676936D01*
X86636Y-676769D01*
X86066D01*
G01X86636D02*
X87016Y-676519D01*
X87333Y-676103D01*
X87460Y-675603D01*
X87333Y-675103D01*
X87016Y-674686D01*
X86446Y-674436D01*
X85876Y-674519D01*
X85306Y-674853D01*
G01X90216Y-678853D02*
X90660Y-679269D01*
X91166Y-679436D01*
X91673Y-679269D01*
X92116Y-678769D01*
X92433Y-678019D01*
X92560Y-677269D01*
Y-676353D01*
X92433Y-675603D01*
X92116Y-674936D01*
X91736Y-674603D01*
X91293Y-674436D01*
X90786Y-674603D01*
X90406Y-674936D01*
X90153Y-675436D01*
X90026Y-676103D01*
X90153Y-676686D01*
X90470Y-677269D01*
X90850Y-677603D01*
X91293Y-677686D01*
X91800Y-677519D01*
X92180Y-677103D01*
X92560Y-676353D01*
G01X96266Y-679436D02*
X96393Y-678353D01*
X96583Y-677436D01*
X96836Y-676603D01*
X97153Y-675686D01*
X97660Y-674436D01*
X95126D01*
G01X100670Y-677769D02*
X102316D01*
G01X105200Y-678436D02*
X105580Y-679019D01*
X106086Y-679353D01*
X106656Y-679436D01*
X107163Y-679353D01*
X107670Y-678936D01*
X107986Y-678436D01*
X108050Y-677936D01*
X107923Y-677353D01*
X107480Y-676936D01*
X107036Y-676769D01*
X106466D01*
G01X107036D02*
X107416Y-676519D01*
X107733Y-676103D01*
X107860Y-675603D01*
X107733Y-675103D01*
X107416Y-674686D01*
X106846Y-674436D01*
X106276Y-674519D01*
X105706Y-674853D01*
G01X110490Y-677353D02*
X110933Y-676769D01*
X111313Y-676436D01*
X111820Y-676269D01*
X112263Y-676436D01*
X112580Y-676769D01*
X112833Y-677269D01*
X112896Y-677853D01*
X112833Y-678353D01*
X112580Y-678853D01*
X112200Y-679269D01*
X111756Y-679436D01*
X111250Y-679269D01*
X110806Y-678769D01*
X110553Y-678019D01*
X110490Y-677186D01*
X110616Y-676103D01*
X110806Y-675519D01*
X111123Y-674936D01*
X111566Y-674519D01*
X112010Y-674436D01*
X112453Y-674603D01*
X112770Y-675019D01*
G01X116793Y-679436D02*
Y-674436D01*
X116033Y-675436D01*
G01Y-679436D02*
X117553D01*
G01X122653D02*
Y-674436D01*
X120310Y-678019D01*
X123476D01*
G01X141693Y-609436D02*
Y-684436D01*
G01Y-659436D02*
X244693D01*
Y-634436D01*
G01X141693D02*
X244693D01*
G01X246693Y-609436D02*
Y-684436D01*
G01X244693Y-609436D02*
Y-684436D01*
G01X252200Y-669436D02*
Y-664436D01*
X253466D01*
X253973Y-664686D01*
X254353Y-665019D01*
X254670Y-665519D01*
X254923Y-666103D01*
X254986Y-666936D01*
X254923Y-667769D01*
X254670Y-668353D01*
X254353Y-668853D01*
X253973Y-669186D01*
X253466Y-669436D01*
X252200D01*
G01X257110D02*
X258693Y-664436D01*
X260276Y-669436D01*
G01X259706Y-667686D02*
X257680D01*
G01X263793Y-664436D02*
Y-669436D01*
G01X262336Y-664436D02*
X265250D01*
G01X270160Y-669436D02*
X267626D01*
Y-664436D01*
X270160D01*
G01X269146Y-666853D02*
X267626D01*
G01X273993Y-669603D02*
X273866Y-669519D01*
Y-669353D01*
X273993Y-669269D01*
X274120Y-669353D01*
Y-669519D01*
X273993Y-669603D01*
G01Y-667353D02*
X273866Y-667269D01*
Y-667103D01*
X273993Y-667019D01*
X274120Y-667103D01*
Y-667269D01*
X273993Y-667353D01*
G01X246693Y-659436D02*
X446693D01*
G01X252326Y-644436D02*
Y-639436D01*
X253846D01*
X254353Y-639686D01*
X254733Y-640269D01*
X254860Y-640936D01*
X254733Y-641603D01*
X254416Y-642103D01*
X253846Y-642353D01*
X252326D01*
G01X257553Y-644603D02*
X259833Y-639436D01*
G01X262336Y-644436D02*
Y-639436D01*
X265250Y-644436D01*
Y-639436D01*
G01X268893Y-644603D02*
X268766Y-644519D01*
Y-644353D01*
X268893Y-644269D01*
X269020Y-644353D01*
Y-644519D01*
X268893Y-644603D01*
G01Y-642353D02*
X268766Y-642269D01*
Y-642103D01*
X268893Y-642019D01*
X269020Y-642103D01*
Y-642269D01*
X268893Y-642353D01*
G01X246693Y-634436D02*
X446693D01*
G01X252326Y-619436D02*
Y-614436D01*
X253846D01*
X254353Y-614686D01*
X254733Y-615269D01*
X254860Y-615936D01*
X254733Y-616603D01*
X254416Y-617103D01*
X253846Y-617353D01*
X252326D01*
G01X257426Y-619436D02*
Y-614436D01*
X259010D01*
X259516Y-614686D01*
X259833Y-615019D01*
X259960Y-615686D01*
X259833Y-616353D01*
X259453Y-616769D01*
X259010Y-617019D01*
X257426D01*
G01X259010D02*
X259960Y-619436D01*
G01X263793D02*
X263286Y-619353D01*
X262843Y-619019D01*
X262463Y-618519D01*
X262210Y-617936D01*
X262083Y-617269D01*
Y-616603D01*
X262210Y-615936D01*
X262463Y-615353D01*
X262843Y-614853D01*
X263286Y-614519D01*
X263793Y-614436D01*
X264300Y-614519D01*
X264743Y-614853D01*
X265123Y-615353D01*
X265376Y-615936D01*
X265503Y-616603D01*
Y-617269D01*
X265376Y-617936D01*
X265123Y-618519D01*
X264743Y-619019D01*
X264300Y-619353D01*
X263793Y-619436D01*
G01X267626Y-618436D02*
X267943Y-618936D01*
X268323Y-619269D01*
X268766Y-619436D01*
X269273Y-619269D01*
X269653Y-618936D01*
X270033Y-618436D01*
X270160Y-617769D01*
Y-614436D01*
G01X275260Y-619436D02*
X272726D01*
Y-614436D01*
X275260D01*
G01X274246Y-616853D02*
X272726D01*
G01X280486Y-614853D02*
X280106Y-614603D01*
X279663Y-614436D01*
X279156D01*
X278586Y-614686D01*
X278143Y-615103D01*
X277826Y-615603D01*
X277573Y-616436D01*
X277510Y-617186D01*
X277636Y-617936D01*
X277826Y-618436D01*
X278206Y-618936D01*
X278650Y-619269D01*
X279093Y-619436D01*
X279536D01*
X279980Y-619269D01*
X280360Y-619019D01*
X280676Y-618686D01*
G01X284193Y-614436D02*
Y-619436D01*
G01X282736Y-614436D02*
X285650D01*
G01X289293Y-619603D02*
X289166Y-619519D01*
Y-619353D01*
X289293Y-619269D01*
X289420Y-619353D01*
Y-619519D01*
X289293Y-619603D01*
G01Y-617353D02*
X289166Y-617269D01*
Y-617103D01*
X289293Y-617019D01*
X289420Y-617103D01*
Y-617269D01*
X289293Y-617353D01*
G01X361693Y-659436D02*
Y-684436D01*
G01X364326Y-661936D02*
Y-666936D01*
X366860D01*
G01X369933Y-661936D02*
X371453D01*
G01X370693D02*
Y-666936D01*
G01X369933D02*
X371453D01*
G01X376300Y-664269D02*
X376553Y-664019D01*
X376743Y-663603D01*
X376870Y-663019D01*
X376743Y-662519D01*
X376490Y-662186D01*
X376046Y-661936D01*
X374336D01*
Y-666936D01*
X376426D01*
X376870Y-666603D01*
X377123Y-666103D01*
X377250Y-665519D01*
X377123Y-664936D01*
X376743Y-664436D01*
X376300Y-664269D01*
X374336D01*
G01X380893Y-667103D02*
X380766Y-667019D01*
Y-666853D01*
X380893Y-666769D01*
X381020Y-666853D01*
Y-667019D01*
X380893Y-667103D01*
G01Y-664853D02*
X380766Y-664769D01*
Y-664603D01*
X380893Y-664519D01*
X381020Y-664603D01*
Y-664769D01*
X380893Y-664853D01*
G01X404693Y-659436D02*
Y-684436D01*
G01Y-634436D02*
Y-659436D01*
G01X412706Y-687603D02*
X412813Y-687478D01*
X412893Y-687269D01*
X412946Y-686978D01*
X412893Y-686728D01*
X412786Y-686561D01*
X412600Y-686436D01*
X411880D01*
Y-688936D01*
X412760D01*
X412946Y-688769D01*
X413053Y-688519D01*
X413106Y-688228D01*
X413053Y-687936D01*
X412893Y-687686D01*
X412706Y-687603D01*
X411880D01*
G01X415173Y-688936D02*
Y-687269D01*
G01Y-687561D02*
X415066Y-687394D01*
X414906Y-687311D01*
X414720Y-687269D01*
X414533Y-687353D01*
X414373Y-687519D01*
X414266Y-687769D01*
X414213Y-688103D01*
X414266Y-688436D01*
X414373Y-688686D01*
X414533Y-688853D01*
X414720Y-688936D01*
X414906Y-688894D01*
X415066Y-688769D01*
X415173Y-688603D01*
G01X416493Y-688644D02*
X416626Y-688811D01*
X416813Y-688936D01*
X416973D01*
X417133Y-688853D01*
X417240Y-688728D01*
X417293Y-688561D01*
X417266Y-688311D01*
X417160Y-688186D01*
X416680Y-687936D01*
X416573Y-687644D01*
X416626Y-687436D01*
X416733Y-687311D01*
X416893Y-687269D01*
X417053Y-687311D01*
X417213Y-687436D01*
G01X418693Y-687811D02*
X419546D01*
X419466Y-687519D01*
X419333Y-687353D01*
X419146Y-687269D01*
X418960Y-687311D01*
X418800Y-687436D01*
X418693Y-687728D01*
X418640Y-687978D01*
Y-688228D01*
X418693Y-688478D01*
X418826Y-688728D01*
X418986Y-688894D01*
X419173Y-688936D01*
X419360Y-688853D01*
X419546Y-688603D01*
G01X420813Y-688936D02*
Y-686436D01*
G01Y-687686D02*
X420946Y-687436D01*
X421106Y-687311D01*
X421266Y-687269D01*
X421506Y-687353D01*
X421666Y-687519D01*
X421773Y-687811D01*
Y-688144D01*
X421720Y-688478D01*
X421613Y-688728D01*
X421426Y-688894D01*
X421266Y-688936D01*
X421106Y-688894D01*
X420946Y-688769D01*
X420813Y-688561D01*
G01X423493Y-688936D02*
X423333Y-688894D01*
X423173Y-688728D01*
X423066Y-688436D01*
X423013Y-688103D01*
X423066Y-687769D01*
X423173Y-687478D01*
X423333Y-687311D01*
X423493Y-687269D01*
X423653Y-687311D01*
X423813Y-687478D01*
X423920Y-687769D01*
X423946Y-688103D01*
X423920Y-688436D01*
X423813Y-688728D01*
X423653Y-688894D01*
X423493Y-688936D01*
G01X426173D02*
Y-687269D01*
G01Y-687561D02*
X426066Y-687394D01*
X425906Y-687311D01*
X425720Y-687269D01*
X425533Y-687353D01*
X425373Y-687519D01*
X425266Y-687769D01*
X425213Y-688103D01*
X425266Y-688436D01*
X425373Y-688686D01*
X425533Y-688853D01*
X425720Y-688936D01*
X425906Y-688894D01*
X426066Y-688769D01*
X426173Y-688603D01*
G01X427520Y-688936D02*
Y-687269D01*
G01Y-687603D02*
X427653Y-687436D01*
X427786Y-687311D01*
X427973Y-687269D01*
X428106Y-687311D01*
X428266Y-687436D01*
G01X430573Y-686436D02*
Y-688936D01*
G01Y-688561D02*
X430466Y-688769D01*
X430306Y-688894D01*
X430120Y-688936D01*
X429906Y-688853D01*
X429746Y-688644D01*
X429640Y-688394D01*
X429613Y-688103D01*
X429640Y-687811D01*
X429746Y-687561D01*
X429906Y-687353D01*
X430120Y-687269D01*
X430306Y-687311D01*
X430440Y-687394D01*
X430573Y-687561D01*
G01X433960Y-688936D02*
Y-686436D01*
X434626D01*
X434840Y-686561D01*
X434973Y-686728D01*
X435026Y-687061D01*
X434973Y-687394D01*
X434813Y-687603D01*
X434626Y-687728D01*
X433960D01*
G01X434626D02*
X435026Y-688936D01*
G01X436293Y-687811D02*
X437146D01*
X437066Y-687519D01*
X436933Y-687353D01*
X436746Y-687269D01*
X436560Y-687311D01*
X436400Y-687436D01*
X436293Y-687728D01*
X436240Y-687978D01*
Y-688228D01*
X436293Y-688478D01*
X436426Y-688728D01*
X436586Y-688894D01*
X436773Y-688936D01*
X436960Y-688853D01*
X437146Y-688603D01*
G01X438413Y-687269D02*
X438893Y-688936D01*
X439373Y-687269D01*
G01X441093Y-689019D02*
X441040Y-688978D01*
Y-688894D01*
X441093Y-688853D01*
X441146Y-688894D01*
Y-688978D01*
X441093Y-689019D01*
G01X443613Y-688936D02*
Y-686436D01*
X442626Y-688228D01*
X443960D01*
G01X444826Y-688936D02*
X445493Y-686436D01*
X446160Y-688936D01*
G01X445920Y-688061D02*
X445066D01*
G01X408593Y-661936D02*
Y-666936D01*
G01X407136Y-661936D02*
X410050D01*
G01X413693Y-666936D02*
X413313Y-666853D01*
X412933Y-666519D01*
X412680Y-665936D01*
X412553Y-665269D01*
X412680Y-664603D01*
X412933Y-664019D01*
X413313Y-663686D01*
X413693Y-663603D01*
X414073Y-663686D01*
X414453Y-664019D01*
X414706Y-664603D01*
X414770Y-665269D01*
X414706Y-665936D01*
X414453Y-666519D01*
X414073Y-666853D01*
X413693Y-666936D01*
G01X418793D02*
X418413Y-666853D01*
X418033Y-666519D01*
X417780Y-665936D01*
X417653Y-665269D01*
X417780Y-664603D01*
X418033Y-664019D01*
X418413Y-663686D01*
X418793Y-663603D01*
X419173Y-663686D01*
X419553Y-664019D01*
X419806Y-664603D01*
X419870Y-665269D01*
X419806Y-665936D01*
X419553Y-666519D01*
X419173Y-666853D01*
X418793Y-666936D01*
G01X423893D02*
Y-661936D01*
G01X428993Y-667103D02*
X428866Y-667019D01*
Y-666853D01*
X428993Y-666769D01*
X429120Y-666853D01*
Y-667019D01*
X428993Y-667103D01*
G01Y-664853D02*
X428866Y-664769D01*
Y-664603D01*
X428993Y-664519D01*
X429120Y-664603D01*
Y-664769D01*
X428993Y-664853D01*
G01X407326Y-641936D02*
Y-636936D01*
X408910D01*
X409416Y-637186D01*
X409733Y-637519D01*
X409860Y-638186D01*
X409733Y-638853D01*
X409353Y-639269D01*
X408910Y-639519D01*
X407326D01*
G01X408910D02*
X409860Y-641936D01*
G01X414960D02*
X412426D01*
Y-636936D01*
X414960D01*
G01X413946Y-639353D02*
X412426D01*
G01X417210Y-636936D02*
X418793Y-641936D01*
X420376Y-636936D01*
G01X423893Y-642103D02*
X423766Y-642019D01*
Y-641853D01*
X423893Y-641769D01*
X424020Y-641853D01*
Y-642019D01*
X423893Y-642103D01*
G01Y-639853D02*
X423766Y-639769D01*
Y-639603D01*
X423893Y-639519D01*
X424020Y-639603D01*
Y-639769D01*
X423893Y-639853D01*
G01X2010999Y-388000D02*
Y1475775D01*
X-407000D01*
Y-386798D01*
Y-755294D01*
Y-793716D01*
X-368578D01*
X1942346D01*
X2010999D01*
Y-725063D01*
Y-388000D01*
G01X-42602Y-671096D02*
X-41975Y-671621D01*
X-41270Y-671936D01*
X-40644D01*
X-40017Y-671621D01*
X-39547Y-671096D01*
X-39312Y-670361D01*
X-39469Y-669626D01*
X-39860Y-668996D01*
X-40565Y-668576D01*
X-41505Y-668366D01*
X-42054Y-667946D01*
X-42289Y-667211D01*
X-42132Y-666476D01*
X-41740Y-665951D01*
X-41192Y-665636D01*
X-40644D01*
X-40095Y-665846D01*
X-39625Y-666371D01*
G01X-36302Y-671936D02*
Y-665636D01*
G01X-33012D02*
Y-671936D01*
G01Y-668786D02*
X-36302D01*
G01X-29297Y-665636D02*
X-27417D01*
G01X-28357D02*
Y-671936D01*
G01X-29297D02*
X-27417D01*
G01X-20490D02*
X-23624D01*
Y-665636D01*
X-20490D01*
G01X-21744Y-668681D02*
X-23624D01*
G01X-17559Y-671936D02*
Y-665636D01*
X-13955Y-671936D01*
Y-665636D01*
G01X-9614Y-673091D02*
X-9300Y-671726D01*
G01X-3157Y-665636D02*
Y-671936D01*
G01X-4959Y-665636D02*
X-1355D01*
G01X1185Y-671936D02*
X3143Y-665636D01*
X5101Y-671936D01*
G01X4396Y-669731D02*
X1890D01*
G01X8503Y-665636D02*
X10383D01*
G01X9443D02*
Y-671936D01*
G01X8503D02*
X10383D01*
G01X13393Y-665636D02*
X14490Y-671936D01*
X15743Y-665636D01*
X16996Y-671936D01*
X18093Y-665636D01*
G01X20085Y-671936D02*
X22043Y-665636D01*
X24001Y-671936D01*
G01X23296Y-669731D02*
X20790D01*
G01X26541Y-671936D02*
Y-665636D01*
X30145Y-671936D01*
Y-665636D01*
G01X39376Y-671936D02*
Y-665636D01*
X41335D01*
X41961Y-665951D01*
X42353Y-666371D01*
X42510Y-667211D01*
X42353Y-668051D01*
X41883Y-668576D01*
X41335Y-668891D01*
X39376D01*
G01X41335D02*
X42510Y-671936D01*
G01X47243Y-672146D02*
X47086Y-672041D01*
Y-671831D01*
X47243Y-671726D01*
X47400Y-671831D01*
Y-672041D01*
X47243Y-672146D01*
G01X53543Y-671936D02*
X52916Y-671831D01*
X52368Y-671411D01*
X51898Y-670781D01*
X51585Y-670046D01*
X51428Y-669206D01*
Y-668366D01*
X51585Y-667526D01*
X51898Y-666791D01*
X52368Y-666161D01*
X52916Y-665741D01*
X53543Y-665636D01*
X54170Y-665741D01*
X54718Y-666161D01*
X55188Y-666791D01*
X55501Y-667526D01*
X55658Y-668366D01*
Y-669206D01*
X55501Y-670046D01*
X55188Y-670781D01*
X54718Y-671411D01*
X54170Y-671831D01*
X53543Y-671936D01*
G01X59843Y-672146D02*
X59686Y-672041D01*
Y-671831D01*
X59843Y-671726D01*
X60000Y-671831D01*
Y-672041D01*
X59843Y-672146D01*
G01X67866Y-666161D02*
X67396Y-665846D01*
X66848Y-665636D01*
X66221D01*
X65516Y-665951D01*
X64968Y-666476D01*
X64576Y-667106D01*
X64263Y-668156D01*
X64185Y-669101D01*
X64341Y-670046D01*
X64576Y-670676D01*
X65046Y-671306D01*
X65595Y-671726D01*
X66143Y-671936D01*
X66691D01*
X67240Y-671726D01*
X67710Y-671411D01*
X68101Y-670991D01*
G01X72443Y-672146D02*
X72286Y-672041D01*
Y-671831D01*
X72443Y-671726D01*
X72600Y-671831D01*
Y-672041D01*
X72443Y-672146D01*
G01X-42680Y-661936D02*
Y-655636D01*
G01X-39704D02*
X-42680Y-659521D01*
G01X-39234Y-661936D02*
X-41349Y-657736D01*
G01X-36380Y-655636D02*
Y-660151D01*
X-36067Y-661096D01*
X-35440Y-661726D01*
X-34657Y-661936D01*
X-33874Y-661726D01*
X-33247Y-661096D01*
X-32934Y-660151D01*
Y-655636D01*
G01X-26790Y-661936D02*
X-29924D01*
Y-655636D01*
X-26790D01*
G01X-28044Y-658681D02*
X-29924D01*
G01X-22997Y-655636D02*
X-21117D01*
G01X-22057D02*
Y-661936D01*
G01X-22997D02*
X-21117D01*
G01X-11102Y-661096D02*
X-10475Y-661621D01*
X-9770Y-661936D01*
X-9144D01*
X-8517Y-661621D01*
X-8047Y-661096D01*
X-7812Y-660361D01*
X-7969Y-659626D01*
X-8360Y-658996D01*
X-9065Y-658576D01*
X-10005Y-658366D01*
X-10554Y-657946D01*
X-10789Y-657211D01*
X-10632Y-656476D01*
X-10240Y-655951D01*
X-9692Y-655636D01*
X-9144D01*
X-8595Y-655846D01*
X-8125Y-656371D01*
G01X-4802Y-661936D02*
Y-655636D01*
G01X-1512D02*
Y-661936D01*
G01Y-658786D02*
X-4802D01*
G01X1185Y-661936D02*
X3143Y-655636D01*
X5101Y-661936D01*
G01X4396Y-659731D02*
X1890D01*
G01X7641Y-661936D02*
Y-655636D01*
X11245Y-661936D01*
Y-655636D01*
G01X20398Y-661936D02*
Y-655636D01*
G01X23688D02*
Y-661936D01*
G01Y-658786D02*
X20398D01*
G01X26698Y-661096D02*
X27325Y-661621D01*
X28030Y-661936D01*
X28656D01*
X29283Y-661621D01*
X29753Y-661096D01*
X29988Y-660361D01*
X29831Y-659626D01*
X29440Y-658996D01*
X28735Y-658576D01*
X27795Y-658366D01*
X27246Y-657946D01*
X27011Y-657211D01*
X27168Y-656476D01*
X27560Y-655951D01*
X28108Y-655636D01*
X28656D01*
X29205Y-655846D01*
X29675Y-656371D01*
G01X33703Y-655636D02*
X35583D01*
G01X34643D02*
Y-661936D01*
G01X33703D02*
X35583D01*
G01X38985D02*
X40943Y-655636D01*
X42901Y-661936D01*
G01X42196Y-659731D02*
X39690D01*
G01X45441Y-661936D02*
Y-655636D01*
X49045Y-661936D01*
Y-655636D01*
G01X54013Y-658786D02*
X55580D01*
Y-660676D01*
X55110Y-661306D01*
X54561Y-661726D01*
X53778Y-661936D01*
X52995Y-661726D01*
X52446Y-661306D01*
X51976Y-660676D01*
X51663Y-659941D01*
X51506Y-659101D01*
Y-658366D01*
X51663Y-657736D01*
X51976Y-657001D01*
X52446Y-656371D01*
X52916Y-655951D01*
X53543Y-655636D01*
X54091D01*
X54718Y-655846D01*
X55188Y-656266D01*
G01X59686Y-663091D02*
X60000Y-661726D01*
G01X66143Y-655636D02*
Y-661936D01*
G01X64341Y-655636D02*
X67945D01*
G01X70485Y-661936D02*
X72443Y-655636D01*
X74401Y-661936D01*
G01X73696Y-659731D02*
X71190D01*
G01X78743Y-661936D02*
X78116Y-661831D01*
X77568Y-661411D01*
X77098Y-660781D01*
X76785Y-660046D01*
X76628Y-659206D01*
Y-658366D01*
X76785Y-657526D01*
X77098Y-656791D01*
X77568Y-656161D01*
X78116Y-655741D01*
X78743Y-655636D01*
X79370Y-655741D01*
X79918Y-656161D01*
X80388Y-656791D01*
X80701Y-657526D01*
X80858Y-658366D01*
Y-659206D01*
X80701Y-660046D01*
X80388Y-660781D01*
X79918Y-661411D01*
X79370Y-661831D01*
X78743Y-661936D01*
G01X91343D02*
Y-659101D01*
X89776Y-655636D01*
G01X92910D02*
X91343Y-659101D01*
G01X95920Y-655636D02*
Y-660151D01*
X96233Y-661096D01*
X96860Y-661726D01*
X97643Y-661936D01*
X98426Y-661726D01*
X99053Y-661096D01*
X99366Y-660151D01*
Y-655636D01*
G01X101985Y-661936D02*
X103943Y-655636D01*
X105901Y-661936D01*
G01X105196Y-659731D02*
X102690D01*
G01X108441Y-661936D02*
Y-655636D01*
X112045Y-661936D01*
Y-655636D01*
G01X-42759Y-651936D02*
Y-645636D01*
X-39155Y-651936D01*
Y-645636D01*
G01X-34657Y-651936D02*
X-35284Y-651831D01*
X-35832Y-651411D01*
X-36302Y-650781D01*
X-36615Y-650046D01*
X-36772Y-649206D01*
Y-648366D01*
X-36615Y-647526D01*
X-36302Y-646791D01*
X-35832Y-646161D01*
X-35284Y-645741D01*
X-34657Y-645636D01*
X-34030Y-645741D01*
X-33482Y-646161D01*
X-33012Y-646791D01*
X-32699Y-647526D01*
X-32542Y-648366D01*
Y-649206D01*
X-32699Y-650046D01*
X-33012Y-650781D01*
X-33482Y-651411D01*
X-34030Y-651831D01*
X-34657Y-651936D01*
G01X-28357Y-652146D02*
X-28514Y-652041D01*
Y-651831D01*
X-28357Y-651726D01*
X-28200Y-651831D01*
Y-652041D01*
X-28357Y-652146D01*
G01X-22057Y-651936D02*
Y-645636D01*
X-22997Y-646896D01*
G01Y-651936D02*
X-21117D01*
G01X-15757D02*
X-15209Y-651831D01*
X-14582Y-651516D01*
X-14190Y-650991D01*
X-14034Y-650256D01*
X-14190Y-649521D01*
X-14660Y-648891D01*
X-15365Y-648576D01*
X-16149D01*
X-16619Y-648366D01*
X-17010Y-647841D01*
X-17167Y-647106D01*
X-16932Y-646371D01*
X-16384Y-645846D01*
X-15757Y-645636D01*
X-15130Y-645846D01*
X-14582Y-646371D01*
X-14347Y-647106D01*
X-14504Y-647841D01*
X-14895Y-648366D01*
X-15365Y-648576D01*
X-16149D01*
X-16854Y-648891D01*
X-17324Y-649521D01*
X-17480Y-650256D01*
X-17324Y-650991D01*
X-16932Y-651516D01*
X-16305Y-651831D01*
X-15757Y-651936D01*
G01X-9457D02*
X-8909Y-651831D01*
X-8282Y-651516D01*
X-7890Y-650991D01*
X-7734Y-650256D01*
X-7890Y-649521D01*
X-8360Y-648891D01*
X-9065Y-648576D01*
X-9849D01*
X-10319Y-648366D01*
X-10710Y-647841D01*
X-10867Y-647106D01*
X-10632Y-646371D01*
X-10084Y-645846D01*
X-9457Y-645636D01*
X-8830Y-645846D01*
X-8282Y-646371D01*
X-8047Y-647106D01*
X-8204Y-647841D01*
X-8595Y-648366D01*
X-9065Y-648576D01*
X-9849D01*
X-10554Y-648891D01*
X-11024Y-649521D01*
X-11180Y-650256D01*
X-11024Y-650991D01*
X-10632Y-651516D01*
X-10005Y-651831D01*
X-9457Y-651936D01*
G01X-3314Y-653091D02*
X-3000Y-651726D01*
G01X793Y-645636D02*
X1890Y-651936D01*
X3143Y-645636D01*
X4396Y-651936D01*
X5493Y-645636D01*
G01X11010Y-651936D02*
X7876D01*
Y-645636D01*
X11010D01*
G01X9756Y-648681D02*
X7876D01*
G01X13941Y-651936D02*
Y-645636D01*
X17545Y-651936D01*
Y-645636D01*
G01X26698Y-651936D02*
Y-645636D01*
G01X29988D02*
Y-651936D01*
G01Y-648786D02*
X26698D01*
G01X32293Y-645636D02*
X33390Y-651936D01*
X34643Y-645636D01*
X35896Y-651936D01*
X36993Y-645636D01*
G01X38985Y-651936D02*
X40943Y-645636D01*
X42901Y-651936D01*
G01X42196Y-649731D02*
X39690D01*
G01X52055Y-646686D02*
X52525Y-646056D01*
X53073Y-645741D01*
X53700Y-645636D01*
X54483Y-645846D01*
X55031Y-646371D01*
X55188Y-647001D01*
X55110Y-647631D01*
X54796Y-648156D01*
X53230Y-649206D01*
X52525Y-649941D01*
X52055Y-650991D01*
X51898Y-651936D01*
X55188D01*
G01X58041D02*
Y-645636D01*
X61645Y-651936D01*
Y-645636D01*
G01X64420Y-651936D02*
Y-645636D01*
X65986D01*
X66613Y-645951D01*
X67083Y-646371D01*
X67475Y-647001D01*
X67788Y-647736D01*
X67866Y-648786D01*
X67788Y-649836D01*
X67475Y-650571D01*
X67083Y-651201D01*
X66613Y-651621D01*
X65986Y-651936D01*
X64420D01*
G01X77176D02*
Y-645636D01*
X79135D01*
X79761Y-645951D01*
X80153Y-646371D01*
X80310Y-647211D01*
X80153Y-648051D01*
X79683Y-648576D01*
X79135Y-648891D01*
X77176D01*
G01X79135D02*
X80310Y-651936D01*
G01X83320D02*
Y-645636D01*
X84886D01*
X85513Y-645951D01*
X85983Y-646371D01*
X86375Y-647001D01*
X86688Y-647736D01*
X86766Y-648786D01*
X86688Y-649836D01*
X86375Y-650571D01*
X85983Y-651201D01*
X85513Y-651621D01*
X84886Y-651936D01*
X83320D01*
G01X91343Y-652146D02*
X91186Y-652041D01*
Y-651831D01*
X91343Y-651726D01*
X91500Y-651831D01*
Y-652041D01*
X91343Y-652146D01*
G01X-18657Y-639236D02*
X-21177Y-638819D01*
X-23382Y-637153D01*
X-25272Y-634653D01*
X-26532Y-631736D01*
X-27162Y-628403D01*
Y-625069D01*
X-26532Y-621736D01*
X-25272Y-618819D01*
X-23382Y-616320D01*
X-21177Y-614653D01*
X-18657Y-614236D01*
X-16137Y-614653D01*
X-13932Y-616320D01*
X-12042Y-618819D01*
X-10782Y-621736D01*
X-10152Y-625069D01*
Y-628403D01*
X-10782Y-631736D01*
X-12042Y-634653D01*
X-13932Y-637153D01*
X-16137Y-638819D01*
X-18657Y-639236D01*
G01X-16137Y-632569D02*
X-12357Y-639236D01*
G01X1188Y-622570D02*
Y-634236D01*
X2448Y-637153D01*
X4338Y-638819D01*
X6543Y-639236D01*
X8748Y-638819D01*
X10638Y-637153D01*
X11898Y-634236D01*
G01Y-639236D02*
Y-622570D01*
G01X37413Y-639236D02*
Y-622570D01*
G01Y-625486D02*
X36153Y-623820D01*
X34263Y-622986D01*
X32058Y-622570D01*
X29853Y-623403D01*
X27963Y-625069D01*
X26703Y-627570D01*
X26073Y-630903D01*
X26703Y-634236D01*
X27963Y-636737D01*
X29853Y-638403D01*
X32058Y-639236D01*
X34263Y-638819D01*
X36153Y-637570D01*
X37413Y-635903D01*
G01X51588Y-639236D02*
Y-622570D01*
G01Y-626736D02*
X52848Y-624653D01*
X54738Y-622986D01*
X57258Y-622570D01*
X59463Y-622986D01*
X61353Y-624653D01*
X62298Y-627570D01*
Y-639236D01*
G01X82143Y-614236D02*
Y-639236D01*
G01X77733Y-622570D02*
X86553D01*
G01X113013Y-639236D02*
Y-622570D01*
G01Y-625486D02*
X111753Y-623820D01*
X109863Y-622986D01*
X107658Y-622570D01*
X105453Y-623403D01*
X103563Y-625069D01*
X102303Y-627570D01*
X101673Y-630903D01*
X102303Y-634236D01*
X103563Y-636737D01*
X105453Y-638403D01*
X107658Y-639236D01*
X109863Y-638819D01*
X111753Y-637570D01*
X113013Y-635903D01*
G01X152693Y-618936D02*
Y-626936D01*
X156693D01*
G01X164493D02*
Y-621603D01*
G01Y-622536D02*
X164093Y-622003D01*
X163493Y-621736D01*
X162793Y-621603D01*
X162093Y-621869D01*
X161493Y-622403D01*
X161093Y-623203D01*
X160893Y-624269D01*
X161093Y-625336D01*
X161493Y-626136D01*
X162093Y-626669D01*
X162793Y-626936D01*
X163493Y-626803D01*
X164093Y-626403D01*
X164493Y-625870D01*
G01X168593Y-629336D02*
X169193Y-629603D01*
X169993Y-629336D01*
X170493Y-628803D01*
X170893Y-628136D01*
X171493Y-626003D01*
X172793Y-621603D01*
G01X169593D02*
X171493Y-626003D01*
G01X177193Y-623336D02*
X180393D01*
X180093Y-622403D01*
X179593Y-621869D01*
X178893Y-621603D01*
X178193Y-621736D01*
X177593Y-622136D01*
X177193Y-623069D01*
X176993Y-623870D01*
Y-624669D01*
X177193Y-625469D01*
X177693Y-626269D01*
X178293Y-626803D01*
X178993Y-626936D01*
X179693Y-626669D01*
X180393Y-625870D01*
G01X185293Y-626936D02*
Y-621603D01*
G01Y-622669D02*
X185793Y-622136D01*
X186293Y-621736D01*
X186993Y-621603D01*
X187493Y-621736D01*
X188093Y-622136D01*
G01X173993Y-676936D02*
Y-668936D01*
G01X177793D02*
X173993Y-673870D01*
G01X178393Y-676936D02*
X175693Y-671603D01*
G01X185993Y-676936D02*
Y-671603D01*
G01Y-672536D02*
X185593Y-672003D01*
X184993Y-671736D01*
X184293Y-671603D01*
X183593Y-671869D01*
X182993Y-672403D01*
X182593Y-673203D01*
X182393Y-674269D01*
X182593Y-675336D01*
X182993Y-676136D01*
X183593Y-676669D01*
X184293Y-676936D01*
X184993Y-676803D01*
X185593Y-676403D01*
X185993Y-675870D01*
G01X192193Y-671603D02*
Y-676936D01*
G01Y-669469D02*
X191993Y-669336D01*
Y-669069D01*
X192193Y-668936D01*
X192393Y-669069D01*
Y-669336D01*
X192193Y-669469D01*
G01X186193Y-643936D02*
Y-651936D01*
G01X183893Y-643936D02*
X188493D01*
G01X194193Y-651936D02*
X193393Y-651803D01*
X192693Y-651269D01*
X192093Y-650469D01*
X191693Y-649536D01*
X191493Y-648469D01*
Y-647403D01*
X191693Y-646336D01*
X192093Y-645403D01*
X192693Y-644603D01*
X193393Y-644069D01*
X194193Y-643936D01*
X194993Y-644069D01*
X195693Y-644603D01*
X196293Y-645403D01*
X196693Y-646336D01*
X196893Y-647403D01*
Y-648469D01*
X196693Y-649536D01*
X196293Y-650469D01*
X195693Y-651269D01*
X194993Y-651803D01*
X194193Y-651936D01*
G01X200193D02*
Y-643936D01*
X202593D01*
X203393Y-644336D01*
X203993Y-645269D01*
X204193Y-646336D01*
X203993Y-647403D01*
X203493Y-648203D01*
X202593Y-648603D01*
X200193D01*
G01X206193Y-626936D02*
Y-618936D01*
X204993Y-620536D01*
G01Y-626936D02*
X207393D01*
G01X279293Y-670269D02*
X279893Y-669469D01*
X280593Y-669069D01*
X281393Y-668936D01*
X282393Y-669203D01*
X283093Y-669869D01*
X283293Y-670669D01*
X283193Y-671470D01*
X282793Y-672136D01*
X280793Y-673469D01*
X279893Y-674403D01*
X279293Y-675736D01*
X279093Y-676936D01*
X283293D01*
G01X289193Y-668936D02*
X288393Y-669203D01*
X287793Y-669869D01*
X287393Y-670669D01*
X287093Y-671736D01*
X286993Y-672936D01*
X287093Y-674136D01*
X287393Y-675203D01*
X287793Y-676003D01*
X288393Y-676669D01*
X289193Y-676936D01*
X289993Y-676669D01*
X290593Y-676003D01*
X290993Y-675203D01*
X291293Y-674136D01*
X291393Y-672936D01*
X291293Y-671736D01*
X290993Y-670669D01*
X290593Y-669869D01*
X289993Y-669203D01*
X289193Y-668936D01*
G01X295293Y-670269D02*
X295893Y-669469D01*
X296593Y-669069D01*
X297393Y-668936D01*
X298393Y-669203D01*
X299093Y-669869D01*
X299293Y-670669D01*
X299193Y-671470D01*
X298793Y-672136D01*
X296793Y-673469D01*
X295893Y-674403D01*
X295293Y-675736D01*
X295093Y-676936D01*
X299293D01*
G01X303293Y-670269D02*
X303893Y-669469D01*
X304593Y-669069D01*
X305393Y-668936D01*
X306393Y-669203D01*
X307093Y-669869D01*
X307293Y-670669D01*
X307193Y-671470D01*
X306793Y-672136D01*
X304793Y-673469D01*
X303893Y-674403D01*
X303293Y-675736D01*
X303093Y-676936D01*
X307293D01*
G01X311393Y-677203D02*
X314993Y-668936D01*
G01X321193Y-676936D02*
Y-668936D01*
X319993Y-670536D01*
G01Y-676936D02*
X322393D01*
G01X327293Y-670269D02*
X327893Y-669469D01*
X328593Y-669069D01*
X329393Y-668936D01*
X330393Y-669203D01*
X331093Y-669869D01*
X331293Y-670669D01*
X331193Y-671470D01*
X330793Y-672136D01*
X328793Y-673469D01*
X327893Y-674403D01*
X327293Y-675736D01*
X327093Y-676936D01*
X331293D01*
G01X335393Y-677203D02*
X338993Y-668936D01*
G01X345193D02*
X344393Y-669203D01*
X343793Y-669869D01*
X343393Y-670669D01*
X343093Y-671736D01*
X342993Y-672936D01*
X343093Y-674136D01*
X343393Y-675203D01*
X343793Y-676003D01*
X344393Y-676669D01*
X345193Y-676936D01*
X345993Y-676669D01*
X346593Y-676003D01*
X346993Y-675203D01*
X347293Y-674136D01*
X347393Y-672936D01*
X347293Y-671736D01*
X346993Y-670669D01*
X346593Y-669869D01*
X345993Y-669203D01*
X345193Y-668936D01*
G01X351493Y-676003D02*
X352193Y-676669D01*
X352993Y-676936D01*
X353793Y-676669D01*
X354493Y-675870D01*
X354993Y-674669D01*
X355193Y-673469D01*
Y-672003D01*
X354993Y-670803D01*
X354493Y-669736D01*
X353893Y-669203D01*
X353193Y-668936D01*
X352393Y-669203D01*
X351793Y-669736D01*
X351393Y-670536D01*
X351193Y-671603D01*
X351393Y-672536D01*
X351893Y-673469D01*
X352493Y-674003D01*
X353193Y-674136D01*
X353993Y-673870D01*
X354593Y-673203D01*
X355193Y-672003D01*
G01X278993Y-651936D02*
Y-643936D01*
X280993D01*
X281793Y-644336D01*
X282393Y-644869D01*
X282893Y-645669D01*
X283293Y-646603D01*
X283393Y-647936D01*
X283293Y-649269D01*
X282893Y-650203D01*
X282393Y-651003D01*
X281793Y-651536D01*
X280993Y-651936D01*
X278993D01*
G01X286693D02*
X289193Y-643936D01*
X291693Y-651936D01*
G01X290793Y-649136D02*
X287593D01*
G01X297193Y-643936D02*
X296393Y-644203D01*
X295793Y-644869D01*
X295393Y-645669D01*
X295093Y-646736D01*
X294993Y-647936D01*
X295093Y-649136D01*
X295393Y-650203D01*
X295793Y-651003D01*
X296393Y-651669D01*
X297193Y-651936D01*
X297993Y-651669D01*
X298593Y-651003D01*
X298993Y-650203D01*
X299293Y-649136D01*
X299393Y-647936D01*
X299293Y-646736D01*
X298993Y-645669D01*
X298593Y-644869D01*
X297993Y-644203D01*
X297193Y-643936D01*
G01X303293Y-651936D02*
Y-643936D01*
X307093D01*
G01X305693Y-647803D02*
X303293D01*
G01X313193Y-643936D02*
X312393Y-644203D01*
X311793Y-644869D01*
X311393Y-645669D01*
X311093Y-646736D01*
X310993Y-647936D01*
X311093Y-649136D01*
X311393Y-650203D01*
X311793Y-651003D01*
X312393Y-651669D01*
X313193Y-651936D01*
X313993Y-651669D01*
X314593Y-651003D01*
X314993Y-650203D01*
X315293Y-649136D01*
X315393Y-647936D01*
X315293Y-646736D01*
X314993Y-645669D01*
X314593Y-644869D01*
X313993Y-644203D01*
X313193Y-643936D01*
G01X321193D02*
Y-651936D01*
G01X318893Y-643936D02*
X323493D01*
G01X326593Y-651936D02*
Y-643936D01*
X329193Y-650603D01*
X331793Y-643936D01*
Y-651936D01*
G01X334993D02*
Y-643936D01*
X336993D01*
X337793Y-644336D01*
X338393Y-644869D01*
X338893Y-645669D01*
X339293Y-646603D01*
X339393Y-647936D01*
X339293Y-649269D01*
X338893Y-650203D01*
X338393Y-651003D01*
X337793Y-651536D01*
X336993Y-651936D01*
X334993D01*
G01X347393Y-644603D02*
X346793Y-644203D01*
X346093Y-643936D01*
X345293D01*
X344393Y-644336D01*
X343693Y-645003D01*
X343193Y-645803D01*
X342793Y-647136D01*
X342693Y-648336D01*
X342893Y-649536D01*
X343193Y-650336D01*
X343793Y-651136D01*
X344493Y-651669D01*
X345193Y-651936D01*
X345893D01*
X346593Y-651669D01*
X347193Y-651269D01*
X347693Y-650736D01*
G01X350993Y-651936D02*
Y-643936D01*
X352993D01*
X353793Y-644336D01*
X354393Y-644869D01*
X354893Y-645669D01*
X355293Y-646603D01*
X355393Y-647936D01*
X355293Y-649269D01*
X354893Y-650203D01*
X354393Y-651003D01*
X353793Y-651536D01*
X352993Y-651936D01*
X350993D01*
G01X361193Y-643936D02*
X360393Y-644203D01*
X359793Y-644869D01*
X359393Y-645669D01*
X359093Y-646736D01*
X358993Y-647936D01*
X359093Y-649136D01*
X359393Y-650203D01*
X359793Y-651003D01*
X360393Y-651669D01*
X361193Y-651936D01*
X361993Y-651669D01*
X362593Y-651003D01*
X362993Y-650203D01*
X363293Y-649136D01*
X363393Y-647936D01*
X363293Y-646736D01*
X362993Y-645669D01*
X362593Y-644869D01*
X361993Y-644203D01*
X361193Y-643936D01*
G01X298418Y-624819D02*
Y-618519D01*
X301394D01*
G01X300298Y-621564D02*
X298418D01*
G01X306206Y-618519D02*
X305579Y-618729D01*
X305109Y-619254D01*
X304796Y-619884D01*
X304561Y-620724D01*
X304483Y-621669D01*
X304561Y-622614D01*
X304796Y-623454D01*
X305109Y-624084D01*
X305579Y-624609D01*
X306206Y-624819D01*
X306833Y-624609D01*
X307303Y-624084D01*
X307616Y-623454D01*
X307851Y-622614D01*
X307929Y-621669D01*
X307851Y-620724D01*
X307616Y-619884D01*
X307303Y-619254D01*
X306833Y-618729D01*
X306206Y-618519D01*
G01X312506D02*
Y-624819D01*
G01X310704Y-618519D02*
X314308D01*
G01X316456Y-626919D02*
X321156D01*
G01X323069Y-624819D02*
Y-618519D01*
X325106Y-623769D01*
X327143Y-618519D01*
Y-624819D01*
G01X332816D02*
Y-620619D01*
G01Y-621354D02*
X332503Y-620934D01*
X332033Y-620724D01*
X331484Y-620619D01*
X330936Y-620829D01*
X330466Y-621249D01*
X330153Y-621879D01*
X329996Y-622719D01*
X330153Y-623559D01*
X330466Y-624189D01*
X330936Y-624609D01*
X331484Y-624819D01*
X332033Y-624714D01*
X332503Y-624399D01*
X332816Y-623979D01*
G01X336374Y-624819D02*
Y-620619D01*
G01Y-621669D02*
X336688Y-621144D01*
X337158Y-620724D01*
X337784Y-620619D01*
X338333Y-620724D01*
X338803Y-621144D01*
X339038Y-621879D01*
Y-624819D01*
G01X345416D02*
Y-620619D01*
G01Y-621354D02*
X345103Y-620934D01*
X344633Y-620724D01*
X344084Y-620619D01*
X343536Y-620829D01*
X343066Y-621249D01*
X342753Y-621879D01*
X342596Y-622719D01*
X342753Y-623559D01*
X343066Y-624189D01*
X343536Y-624609D01*
X344084Y-624819D01*
X344633Y-624714D01*
X345103Y-624399D01*
X345416Y-623979D01*
G01X349209Y-626394D02*
X349758Y-626814D01*
X350384Y-626919D01*
X350933Y-626814D01*
X351403Y-626289D01*
X351716Y-625554D01*
Y-620619D01*
G01Y-621459D02*
X351403Y-621039D01*
X350933Y-620724D01*
X350384Y-620619D01*
X349758Y-620829D01*
X349366Y-621249D01*
X349053Y-621984D01*
X348896Y-622719D01*
X348974Y-623349D01*
X349288Y-624084D01*
X349758Y-624609D01*
X350384Y-624819D01*
X350854Y-624714D01*
X351403Y-624294D01*
X351716Y-623874D01*
G01X355431Y-621984D02*
X357938D01*
X357703Y-621249D01*
X357311Y-620829D01*
X356763Y-620619D01*
X356214Y-620724D01*
X355744Y-621039D01*
X355431Y-621774D01*
X355274Y-622404D01*
Y-623034D01*
X355431Y-623664D01*
X355823Y-624294D01*
X356293Y-624714D01*
X356841Y-624819D01*
X357389Y-624609D01*
X357938Y-623979D01*
G01X360556Y-624819D02*
Y-620619D01*
G01Y-621774D02*
X360791Y-621249D01*
X361183Y-620829D01*
X361731Y-620619D01*
X362279Y-620829D01*
X362671Y-621249D01*
X362906Y-621774D01*
Y-624819D01*
G01Y-621774D02*
X363141Y-621249D01*
X363533Y-620829D01*
X364081Y-620619D01*
X364629Y-620829D01*
X365021Y-621249D01*
X365256Y-621879D01*
Y-624819D01*
G01X368031Y-621984D02*
X370538D01*
X370303Y-621249D01*
X369911Y-620829D01*
X369363Y-620619D01*
X368814Y-620724D01*
X368344Y-621039D01*
X368031Y-621774D01*
X367874Y-622404D01*
Y-623034D01*
X368031Y-623664D01*
X368423Y-624294D01*
X368893Y-624714D01*
X369441Y-624819D01*
X369989Y-624609D01*
X370538Y-623979D01*
G01X374174Y-624819D02*
Y-620619D01*
G01Y-621669D02*
X374488Y-621144D01*
X374958Y-620724D01*
X375584Y-620619D01*
X376133Y-620724D01*
X376603Y-621144D01*
X376838Y-621879D01*
Y-624819D01*
G01X381806Y-618519D02*
Y-624819D01*
G01X380709Y-620619D02*
X382903D01*
G01X385756Y-626919D02*
X390456D01*
G01X395033Y-621459D02*
X395346Y-621144D01*
X395581Y-620619D01*
X395738Y-619884D01*
X395581Y-619254D01*
X395268Y-618834D01*
X394719Y-618519D01*
X392604D01*
Y-624819D01*
X395189D01*
X395738Y-624399D01*
X396051Y-623769D01*
X396208Y-623034D01*
X396051Y-622299D01*
X395581Y-621669D01*
X395033Y-621459D01*
X392604D01*
G01X398983Y-624819D02*
Y-618519D01*
X400549D01*
X401176Y-618834D01*
X401646Y-619254D01*
X402038Y-619884D01*
X402351Y-620619D01*
X402429Y-621669D01*
X402351Y-622719D01*
X402038Y-623454D01*
X401646Y-624084D01*
X401176Y-624504D01*
X400549Y-624819D01*
X398983D01*
G01X367693Y-679936D02*
Y-671936D01*
X366493Y-673536D01*
G01Y-679936D02*
X368893D01*
G01X373793Y-676603D02*
X374493Y-675669D01*
X375093Y-675136D01*
X375893Y-674869D01*
X376593Y-675136D01*
X377093Y-675669D01*
X377493Y-676469D01*
X377593Y-677403D01*
X377493Y-678203D01*
X377093Y-679003D01*
X376493Y-679669D01*
X375793Y-679936D01*
X374993Y-679669D01*
X374293Y-678870D01*
X373893Y-677669D01*
X373793Y-676336D01*
X373993Y-674603D01*
X374293Y-673669D01*
X374793Y-672736D01*
X375493Y-672069D01*
X376193Y-671936D01*
X376893Y-672203D01*
X377393Y-672869D01*
G01X383693Y-680203D02*
X383493Y-680069D01*
Y-679803D01*
X383693Y-679669D01*
X383893Y-679803D01*
Y-680069D01*
X383693Y-680203D01*
G01X389793Y-676603D02*
X390493Y-675669D01*
X391093Y-675136D01*
X391893Y-674869D01*
X392593Y-675136D01*
X393093Y-675669D01*
X393493Y-676469D01*
X393593Y-677403D01*
X393493Y-678203D01*
X393093Y-679003D01*
X392493Y-679669D01*
X391793Y-679936D01*
X390993Y-679669D01*
X390293Y-678870D01*
X389893Y-677669D01*
X389793Y-676336D01*
X389993Y-674603D01*
X390293Y-673669D01*
X390793Y-672736D01*
X391493Y-672069D01*
X392193Y-671936D01*
X392893Y-672203D01*
X393393Y-672869D01*
G01X412693Y-679936D02*
Y-671936D01*
X411493Y-673536D01*
G01Y-679936D02*
X413893D01*
G01X420493D02*
X420693Y-678203D01*
X420993Y-676736D01*
X421393Y-675403D01*
X421893Y-673936D01*
X422693Y-671936D01*
X418693D01*
G01X428693Y-680203D02*
X428493Y-680069D01*
Y-679803D01*
X428693Y-679669D01*
X428893Y-679803D01*
Y-680069D01*
X428693Y-680203D01*
G01X434793Y-673269D02*
X435393Y-672469D01*
X436093Y-672069D01*
X436893Y-671936D01*
X437893Y-672203D01*
X438593Y-672869D01*
X438793Y-673669D01*
X438693Y-674470D01*
X438293Y-675136D01*
X436293Y-676469D01*
X435393Y-677403D01*
X434793Y-678736D01*
X434593Y-679936D01*
X438793D01*
G01X432493Y-654936D02*
Y-646936D01*
X434493D01*
X435293Y-647336D01*
X435893Y-647869D01*
X436393Y-648669D01*
X436793Y-649603D01*
X436893Y-650936D01*
X436793Y-652269D01*
X436393Y-653203D01*
X435893Y-654003D01*
X435293Y-654536D01*
X434493Y-654936D01*
X432493D01*
G54D22*
X17000Y317016D03*
X20205Y252653D03*
X21000Y317016D03*
X42392Y195803D03*
X46392D03*
X44375Y252626D03*
X44470Y263916D03*
X40500Y357016D03*
X47500Y352016D03*
X40500Y385516D03*
Y392516D03*
X40800Y423516D03*
X52500Y70016D03*
X52055Y123714D03*
X50392Y195803D03*
X60400Y186916D03*
X51849Y203274D03*
X61200Y276916D03*
X61000Y328016D03*
X63000Y403016D03*
X64000Y130216D03*
X75500Y155016D03*
X72800Y180816D03*
X65100Y277016D03*
X74500Y274016D03*
X64900Y328016D03*
X76500Y328146D03*
X68800Y328316D03*
X75000Y403016D03*
X66250Y418266D03*
X91925Y119112D03*
X92405Y131997D03*
X81500Y167416D03*
X83500Y269516D03*
X87500D03*
X79500D03*
X92500Y403016D03*
X88500D03*
X84500D03*
X108500Y39016D03*
X106800Y85016D03*
X101500Y258016D03*
X97300Y257816D03*
X100500Y403016D03*
X104500D03*
X108500D03*
X116500Y39016D03*
X120331Y240016D03*
X122500Y253716D03*
X121918Y328504D03*
X116500Y403116D03*
X119100Y396316D03*
X112500Y403016D03*
X126200Y79516D03*
X132900Y181216D03*
X138000Y208016D03*
X132398Y224708D03*
X128720Y224706D03*
X137918Y328504D03*
X125918D03*
X129300Y426016D03*
X145500Y140516D03*
X148387Y150231D03*
X148400Y164616D03*
X148370Y172266D03*
X142150Y184091D03*
X149500Y229516D03*
X145600Y235416D03*
X142300Y275716D03*
X141918Y328504D03*
X143945Y348664D03*
X147900Y348616D03*
X143000Y419516D03*
X145200Y429466D03*
X163673Y85746D03*
X159673D03*
X159120Y119136D03*
X156500Y132516D03*
X160032Y216735D03*
X153500Y229016D03*
X164801Y257477D03*
X160973Y249527D03*
X153918Y328504D03*
X165026Y343712D03*
X157600Y429516D03*
X161450D03*
X173097Y85746D03*
X169097D03*
X171900Y134916D03*
X177413Y249527D03*
X173992Y257477D03*
X169967D03*
X171276Y423712D03*
X181400Y429716D03*
X175100Y423416D03*
X183800Y120016D03*
X195983Y134885D03*
X188000Y134916D03*
X192000D03*
X183413Y250227D03*
X191538Y250352D03*
X187550Y259756D03*
X193750Y368266D03*
X210778Y108860D03*
X212757Y134885D03*
X208627D03*
X204063Y250302D03*
X211700Y429216D03*
X207300D03*
X215000Y41016D03*
X214785Y108858D03*
X221278Y134885D03*
X217262D03*
X225284D03*
X220600Y324816D03*
X222800Y376291D03*
X213500Y386016D03*
X226500Y403816D03*
X219600Y429216D03*
X215700D03*
X234600Y108016D03*
X229396Y134885D03*
X238500Y332016D03*
X242500Y340516D03*
X243700Y106116D03*
X254332Y114174D03*
X250212Y135803D03*
X246205D03*
X256128Y250195D03*
X250505Y250169D03*
X242940Y258482D03*
X269800Y102416D03*
X258339Y114174D03*
X271674Y145320D03*
X272037Y245468D03*
X269400Y281516D03*
X267000Y416916D03*
X271900Y423816D03*
X257900Y423716D03*
X261900D03*
X277000Y44516D03*
X281300Y108416D03*
X285295Y120397D03*
X281250Y116016D03*
X277200D03*
X275684Y145320D03*
X279582Y245668D03*
X273250Y272516D03*
X284475Y372024D03*
X290000Y62516D03*
X301936Y146388D03*
X292000Y291016D03*
X299000Y291516D03*
X316066Y102834D03*
X316700Y119916D03*
X309936Y146388D03*
X313936D03*
X305936D03*
X311000Y323516D03*
X329825Y275913D03*
X330900Y317416D03*
X337223Y230573D03*
X337600Y275916D03*
G54D106*
X197200Y71000D03*
Y80000D03*
X208800Y71000D03*
Y80000D03*
G54D40*
X28737Y258413D03*
X32673D03*
X30705D03*
X32673Y251721D03*
X28737D03*
G54D115*
X271500Y47559D03*
Y42441D03*
X264500D03*
Y45000D03*
Y47559D03*
X286000Y51941D03*
Y54500D03*
Y57059D03*
X293000D03*
Y51941D03*
G54D31*
X22282Y190078D03*
X33306Y203464D03*
G54D124*
X378560Y-162441D03*
X376592D03*
X376680Y14881D03*
X378648D03*
X378588Y65831D03*
X376620D03*
X376680Y384153D03*
X378648D03*
X399734Y261650D03*
X397766D03*
Y409210D03*
X399734D03*
X409734Y-67622D03*
X407766D03*
Y210938D03*
X409734D03*
G54D13*
X14961Y10591D03*
X48031D03*
X261418Y12166D03*
X294488D03*
X306300Y10591D03*
X339370D03*
G54D134*
G01X376592Y-162441D02*
X375876Y-159873D01*
G01X376680Y14881D02*
X375964Y12313D01*
G01X376620Y65831D02*
X375904Y68399D01*
G01X376680Y384153D02*
X375964Y381585D01*
G01X378560Y-162441D02*
X379276Y-159873D01*
G01X378648Y14881D02*
X379364Y12313D01*
G01X378588Y65831D02*
X379304Y68399D01*
G01X378648Y384153D02*
X379364Y381585D01*
G54D23*
X16916Y328600D03*
X33816Y214700D03*
X27181Y246113D03*
X27816Y264500D03*
X25216Y316900D03*
X37016Y38000D03*
X42500Y214718D03*
X43616Y241000D03*
X44416Y248800D03*
X36508Y246116D03*
X43616Y244900D03*
X48816Y260800D03*
X34816Y264500D03*
X47016Y328000D03*
Y324000D03*
Y344000D03*
Y348000D03*
Y364000D03*
Y368000D03*
Y372000D03*
Y376000D03*
Y380000D03*
Y384000D03*
X47416Y394350D03*
X50732Y38500D03*
X63491Y116450D03*
X51666Y211200D03*
X78082Y118216D03*
X74535Y135866D03*
X91506Y428020D03*
X108016Y102000D03*
Y107500D03*
X115116Y102000D03*
Y107600D03*
X114516Y123500D03*
X118816Y346400D03*
Y342500D03*
X116016Y415000D03*
X127516Y50000D03*
X134016Y201500D03*
X130516Y253700D03*
X129716Y261900D03*
X136916Y348300D03*
Y351900D03*
X133116Y429000D03*
X149516Y142000D03*
X140516Y175200D03*
X140526Y179160D03*
X148610Y182594D03*
X146596Y419250D03*
X150516Y429000D03*
X163316Y112800D03*
X156421Y153077D03*
X155625Y182644D03*
X155732Y178679D03*
X155716Y174800D03*
X155766Y187354D03*
X155816Y191700D03*
X156516Y224000D03*
X155315Y313560D03*
X155316Y309700D03*
X158016Y350500D03*
X183016Y88000D03*
Y92000D03*
X171416Y272800D03*
X187016Y267000D03*
X194016Y264810D03*
X184616Y294500D03*
X189216Y311100D03*
X207656Y244900D03*
X206816Y419600D03*
X214436Y102014D03*
X222136Y258930D03*
X223016Y296600D03*
Y300600D03*
X217916Y416000D03*
X233316Y319400D03*
X254316Y98600D03*
Y95100D03*
X252116Y110300D03*
X266977Y368610D03*
Y381075D03*
X281226Y93260D03*
X273736Y99350D03*
X283074Y138403D03*
X294516Y79500D03*
X289016Y100400D03*
X294776Y142907D03*
X297516Y311500D03*
X290241Y358508D03*
Y363008D03*
X289777Y387500D03*
X303016Y79500D03*
X305397Y273256D03*
X326143Y144423D03*
X321396Y275940D03*
X320175Y294816D03*
X334316Y70000D03*
X334341Y154911D03*
Y164911D03*
Y159911D03*
Y169911D03*
Y179911D03*
Y174911D03*
Y183926D03*
Y189911D03*
X333840Y292085D03*
G54D32*
X26613Y191653D03*
X28975D03*
Y201889D03*
G54D107*
X197111Y88586D03*
Y92326D03*
Y96066D03*
X205969Y92326D03*
Y88586D03*
Y96066D03*
G54D50*
X47059Y64760D03*
X44500D03*
X41941D03*
Y72240D03*
X44500D03*
X47059D03*
G54D116*
X295402Y45224D03*
Y41878D03*
G54D41*
X30705Y252508D03*
G54D125*
X441000Y-444000D03*
X451000D03*
Y-355000D03*
X441000D03*
Y-323400D03*
X451000D03*
Y-245000D03*
X441000D03*
X451000Y-215000D03*
X441000D03*
Y-136600D03*
X451000D03*
Y-107000D03*
X441000D03*
Y-18000D03*
X451000D03*
X441000Y12000D03*
X451000D03*
Y96000D03*
X441000D03*
Y126000D03*
X451000D03*
Y200000D03*
X441000D03*
X451000Y230000D03*
X441000D03*
Y304000D03*
X451000D03*
Y336000D03*
X441000D03*
Y420000D03*
X451000D03*
G54D14*
X17716Y18465D03*
X45276D03*
X264173Y20040D03*
X291733D03*
X309055Y18465D03*
X336615D03*
G54D135*
G01X33306Y192047D02*
X34766D01*
X36599Y190214D01*
Y189016D01*
G01X33306Y193621D02*
X35031D01*
X37802Y190850D01*
X38615Y190513D01*
G01X33306Y196771D02*
X36640D01*
X37015Y196396D01*
X38471D01*
X39399Y196012D01*
X39408Y195990D01*
G01X33306Y199921D02*
X34885D01*
X35714Y200750D01*
X40504D01*
X42392Y198862D01*
G01X37823Y198346D02*
X39853D01*
X41408Y196791D01*
Y196696D01*
X42392Y195712D01*
G54D42*
X26768Y251327D03*
G54D24*
X17000Y319983D03*
X20205Y255620D03*
X21000Y319983D03*
X42392Y198770D03*
X46392D03*
X44375Y255593D03*
X44470Y266883D03*
X40500Y359983D03*
X47500Y354983D03*
X40500Y388483D03*
Y395483D03*
X40800Y426483D03*
X52500Y72983D03*
X52055Y126681D03*
X60400Y189883D03*
X51849Y206241D03*
X50392Y198770D03*
X61200Y279883D03*
X61000Y330983D03*
X63000Y405983D03*
X64000Y133183D03*
X75500Y157983D03*
X72800Y183783D03*
X65100Y279983D03*
X74500Y276983D03*
X64900Y330983D03*
X76500Y331113D03*
X68800Y331283D03*
X75000Y405983D03*
X66250Y421233D03*
X91925Y122079D03*
X92405Y134964D03*
X81500Y170383D03*
X83500Y272483D03*
X87500D03*
X79500D03*
X92500Y405983D03*
X88500D03*
X84500D03*
X108500Y41983D03*
X106800Y87983D03*
X101500Y260983D03*
X97300Y260783D03*
X100500Y405983D03*
X104500D03*
X108500D03*
X116500Y41983D03*
X120331Y242983D03*
X122500Y256683D03*
X121918Y331471D03*
X116500Y406083D03*
X119100Y399283D03*
X112500Y405983D03*
X126200Y82483D03*
X132900Y184183D03*
X138000Y210983D03*
X132398Y227675D03*
X128720Y227673D03*
X137918Y331471D03*
X125918D03*
X129300Y428983D03*
X145500Y143483D03*
X148387Y153198D03*
X148400Y167583D03*
X148370Y175233D03*
X142150Y187058D03*
X149500Y232483D03*
X145600Y238383D03*
X142300Y278683D03*
X141918Y331471D03*
X143945Y351631D03*
X147900Y351583D03*
X145200Y432433D03*
X143000Y422483D03*
X163673Y88713D03*
X159673D03*
X159120Y122103D03*
X156500Y135483D03*
X160032Y219702D03*
X153500Y231983D03*
X160973Y252494D03*
X164801Y260444D03*
X153918Y331471D03*
X165026Y346679D03*
X157600Y432483D03*
X161450D03*
X173097Y88713D03*
X169097D03*
X171900Y137883D03*
X177413Y252494D03*
X173992Y260444D03*
X169967D03*
X171276Y426679D03*
X181400Y432683D03*
X175100Y426383D03*
X183800Y122983D03*
X195983Y137852D03*
X188000Y137883D03*
X192000D03*
X183413Y253194D03*
X191538Y253319D03*
X187550Y262723D03*
X193750Y371233D03*
X210778Y111827D03*
X212757Y137852D03*
X208627D03*
X204063Y253269D03*
X211700Y432183D03*
X207300D03*
X215000Y43983D03*
X214785Y111825D03*
X221278Y137852D03*
X217262D03*
X225284D03*
X220600Y327783D03*
X213500Y388983D03*
X222800Y379258D03*
X226500Y406783D03*
X219600Y432183D03*
X215700D03*
X234600Y110983D03*
X229396Y137852D03*
X238500Y334983D03*
X242500Y343483D03*
X254332Y117141D03*
X243700Y109083D03*
X250212Y138770D03*
X246205D03*
X256128Y253162D03*
X250505Y253136D03*
X242940Y261449D03*
X269800Y105383D03*
X258339Y117141D03*
X271674Y148287D03*
X272037Y248435D03*
X269400Y284483D03*
X267000Y419883D03*
X271900Y426783D03*
X257900Y426683D03*
X261900D03*
X277000Y47483D03*
X285295Y123364D03*
X281250Y118983D03*
X281300Y111383D03*
X277200Y118983D03*
X275684Y148287D03*
X279582Y248635D03*
X273250Y275483D03*
X284475Y374991D03*
X290000Y65483D03*
X301936Y149355D03*
X292000Y293983D03*
X299000Y294483D03*
X316066Y105801D03*
X316700Y122883D03*
X309936Y149355D03*
X313936D03*
X305936D03*
X311000Y326483D03*
X329825Y278880D03*
X330900Y320383D03*
X337223Y233540D03*
X337600Y278883D03*
G54D15*
X22047Y46417D03*
X333466D03*
G54D60*
X63300Y241363D03*
X60741D03*
Y249237D03*
X63300D03*
X65859Y241363D03*
Y249237D03*
X90059Y241363D03*
X87500D03*
X84941D03*
Y249237D03*
X87500D03*
X90059D03*
G54D108*
X197012Y296565D03*
Y304635D03*
X210988Y296565D03*
Y304635D03*
G54D33*
X33109Y190078D03*
G54D126*
X441000Y-454000D03*
X451000D03*
Y-345000D03*
X441000D03*
Y-333400D03*
X451000D03*
Y-235000D03*
X441000D03*
X451000Y-225000D03*
X441000D03*
Y-126600D03*
X451000D03*
Y-117000D03*
X441000D03*
Y-8000D03*
X451000D03*
X441000Y2000D03*
X451000D03*
Y106000D03*
X441000D03*
Y116000D03*
X451000D03*
Y210000D03*
X441000D03*
X451000Y220000D03*
X441000D03*
Y314000D03*
X451000D03*
Y326000D03*
X441000D03*
Y430000D03*
X451000D03*
G54D117*
X293907Y164990D03*
X290757D03*
X287608D03*
X293907Y168140D03*
X290757D03*
X287608D03*
X293907Y171289D03*
X290757D03*
X287608D03*
X293907Y174439D03*
X290757D03*
X287608D03*
X293907Y177588D03*
X290757D03*
X287608D03*
X293907Y180738D03*
X290757D03*
X287608D03*
X293907Y183888D03*
X290757D03*
X287608D03*
X293907Y187037D03*
X290757D03*
X287608D03*
X293907Y190187D03*
X290757D03*
X287608D03*
X293907Y193336D03*
X290757D03*
X287608D03*
X293907Y196486D03*
X290757D03*
X287608D03*
X293907Y199636D03*
X290757D03*
X287608D03*
X293907Y202785D03*
X290757D03*
X287608D03*
X293907Y205935D03*
X290757D03*
X287608D03*
X293907Y209084D03*
X290757D03*
X287608D03*
X293907Y212234D03*
X290757D03*
X287608D03*
X312804Y164990D03*
X309655D03*
X306505D03*
X312804Y168140D03*
X309655D03*
X306505D03*
X312804Y171289D03*
X309655D03*
X306505D03*
X312804Y174439D03*
X309655D03*
X306505D03*
X312804Y177588D03*
X309655D03*
X306505D03*
X312804Y180738D03*
X309655D03*
X306505D03*
X312804Y183888D03*
X309655D03*
X306505D03*
X312804Y187037D03*
X309655D03*
X306505D03*
X312804Y190187D03*
X309655D03*
X306505D03*
X312804Y193336D03*
X309655D03*
X306505D03*
X312804Y196486D03*
X309655D03*
X306505D03*
X312804Y199636D03*
X309655D03*
X306505D03*
X312804Y202785D03*
X309655D03*
X306505D03*
X312804Y205935D03*
X309655D03*
X306505D03*
X312804Y209084D03*
X309655D03*
X306505D03*
X312804Y212234D03*
X309655D03*
X306505D03*
G54D51*
X45276Y89000D03*
Y109000D03*
X56102Y99000D03*
X197587Y338200D03*
X208413Y328200D03*
Y348200D03*
X254087Y69500D03*
X264913Y59500D03*
Y79500D03*
G54D136*
G01X33306Y195196D02*
X36386D01*
X37360Y194222D01*
Y194050D01*
G01X37823Y198346D02*
X33306D01*
G54D127*
G01X15688Y259063D02*
X17436D01*
X18150Y259777D01*
G01X38615Y190513D02*
X39538D01*
X41251Y188800D01*
X42869D01*
X44144Y187525D01*
G01X32673Y251721D02*
Y249228D01*
X35785Y246116D01*
X36417D01*
G01X30875Y264500D02*
X34725D01*
G01X24705Y258767D02*
X24745Y258807D01*
X26768D01*
G01X21300Y259777D02*
X23695D01*
X24705Y258767D01*
G01X37875Y264500D02*
Y263776D01*
X36599Y262500D01*
X31505D01*
X30705Y261700D01*
Y258413D01*
G01X47294Y184491D02*
X44063D01*
X41730Y186824D01*
X38791D01*
X36599Y189016D01*
G01X39408Y195990D02*
X39367Y195890D01*
X40365Y193481D01*
X42311Y191535D01*
G01X51575Y211200D02*
X50875Y211900D01*
X48041D01*
X47714Y212227D01*
G01X50392Y198862D02*
X46392D01*
G01D02*
X42392D01*
G01X44375Y252535D02*
X48440D01*
G01X44375D02*
X39746D01*
X38198Y254083D01*
X36414D01*
G01X37485Y258807D02*
X34642D01*
G01X41329Y259638D02*
X39656D01*
X38825Y258807D01*
X37485D01*
G01X60090Y126235D02*
X60095Y126230D01*
X63918D01*
G01X59575Y183000D02*
X59441Y182866D01*
Y148589D01*
G01X57141Y204989D02*
Y209341D01*
G01X48440Y252535D02*
X52440D01*
G01X66550Y116450D02*
Y118310D01*
X69710Y121470D01*
X73089D01*
X74095Y122476D01*
Y123474D01*
G01X66830Y122329D02*
X67330D01*
X69262Y124261D01*
X70354D01*
G01X67126Y128100D02*
X67224Y128198D01*
X70354D01*
G01X66874Y130590D02*
X67910D01*
X68333Y130167D01*
X70354D01*
G01Y126230D02*
X68968D01*
X68038Y125300D01*
X66900D01*
G01D02*
X66600D01*
X65670Y126230D01*
X63918D01*
G01X72500Y258360D02*
Y255001D01*
X73447Y254054D01*
Y250715D01*
G01X73000Y323400D02*
X73300D01*
X74803Y321897D01*
Y318544D01*
G01X81772Y124261D02*
X82739D01*
X85115Y121885D01*
X88071D01*
X88083Y121897D01*
G01X100000Y92925D02*
X101425D01*
X101990Y93490D01*
X102400Y94484D01*
Y102400D01*
X102700Y102700D01*
Y123460D01*
X101460Y124700D01*
X99700D01*
X98600Y125800D01*
Y128000D01*
X97000Y129600D01*
X90600D01*
X89900Y130300D01*
X86200D01*
X84098Y128198D01*
X81772D01*
G01X79353Y240085D02*
Y240499D01*
X80354Y241500D01*
X81600D01*
G01X91535Y288821D02*
Y285435D01*
X90100Y284000D01*
X85687D01*
X85672Y283985D01*
G01D02*
X85630Y284027D01*
Y288821D01*
G01X90551Y318544D02*
Y322692D01*
X89843Y323400D01*
X85500D01*
G01X105916Y109952D02*
X106120Y110156D01*
Y120420D01*
X109200Y123500D01*
G01X103500Y240619D02*
X102866Y239985D01*
X101253D01*
G01X95347Y250615D02*
Y256762D01*
X95192Y256917D01*
Y257317D01*
X93584Y258925D01*
X93500D01*
G01X97441Y288821D02*
X97341Y288721D01*
Y283590D01*
X97440D01*
G01D02*
X98440Y284590D01*
X102347D01*
X103347Y285590D01*
Y288821D01*
G01X118009Y311200D02*
X113500D01*
X110480Y314220D01*
X107380D01*
X106299Y315301D01*
Y318544D01*
G01X96457D02*
Y323194D01*
G01X100394Y318544D02*
Y321690D01*
X98890Y323194D01*
X96457D01*
G01X112800Y242060D02*
Y244380D01*
X113590Y245170D01*
G01X115260Y268126D02*
X115774D01*
X117400Y266500D01*
G01D02*
X119026Y268126D01*
X119760D01*
G01X117900Y313810D02*
X118009D01*
G01X118110Y318544D02*
Y314020D01*
X117900Y313810D01*
G01D02*
X113290D01*
X112205Y314895D01*
Y318544D01*
G01X136319Y104803D02*
X133497D01*
X132100Y106200D01*
Y108500D01*
X129300Y111300D01*
X126691D01*
X126575Y111416D01*
G01X132500Y167300D02*
X133500Y166300D01*
Y163615D01*
G01X128760Y268126D02*
Y265726D01*
G01X133000Y267925D02*
X132799Y268126D01*
X128760D01*
G01X124016Y318544D02*
Y313784D01*
G01X135827Y318544D02*
Y314254D01*
X135300Y313727D01*
X135462D01*
G01D02*
X140627D01*
X141732Y314832D01*
Y318544D01*
G01X129921Y312600D02*
X129868Y312547D01*
X128453D01*
X127216Y313784D01*
X124016D01*
G01X135462Y313727D02*
X134335Y312600D01*
X129921D01*
G01D02*
Y318544D01*
G01X164500Y266000D02*
X166200Y267700D01*
Y276600D01*
X166900Y277300D01*
X169770D01*
X170785Y276285D01*
Y276221D01*
X172414Y274592D01*
X173586D01*
X174294Y275300D01*
X179500D01*
X180975Y273825D01*
Y272800D01*
G01X179902Y195950D02*
X178346Y197506D01*
G01X179902Y192800D02*
X178346Y191244D01*
G01X183051Y192800D02*
X181495Y191244D01*
G01X176752Y195950D02*
X175196Y197506D01*
G01X176752Y192800D02*
X174336D01*
G01X170800Y193100D02*
Y191900D01*
X171900Y190800D01*
X175603D01*
X176752Y189651D01*
G01X180975Y272800D02*
X181100Y272675D01*
Y268700D01*
X179200Y266800D01*
X176953D01*
G01X171325Y272800D02*
Y267078D01*
X171047Y266800D01*
G01X186201Y192800D02*
X184645Y191244D01*
G01X186201Y189651D02*
X184645Y188095D01*
G01X228832Y107236D02*
Y105000D01*
X227332Y103500D01*
X224200D01*
X223700Y104000D01*
X215099D01*
X212500Y106599D01*
Y107047D01*
X210778Y108769D01*
G01X209824Y106122D02*
X207978D01*
X204700Y109400D01*
Y112300D01*
X207153Y114753D01*
X215954D01*
X217900Y116699D01*
Y121500D01*
X221500Y125100D01*
G01X212067Y465590D02*
Y461533D01*
X215000Y458600D01*
G01X231100Y125600D02*
X230800Y124178D01*
Y122022D01*
X232393Y117900D01*
Y116637D01*
X236900Y112130D01*
Y109628D01*
X237430Y109098D01*
Y107660D01*
X237280Y107510D01*
G01D02*
X237872Y107205D01*
X238100Y106486D01*
Y104620D01*
X236360Y102880D01*
X233645D01*
X232635Y103890D01*
X232210D01*
X228864Y107236D01*
X228832D01*
G01X233511Y134994D02*
X233711Y134794D01*
X235579D01*
X235671Y134886D01*
X237563D01*
X237655Y134794D01*
G01X233511Y132594D02*
Y134994D01*
G01X251800Y416600D02*
X250900D01*
X246640Y412340D01*
X238548Y408988D01*
X236860Y407300D01*
G01X252025Y110300D02*
Y107939D01*
X252300Y107664D01*
G01X254010Y423639D02*
Y418810D01*
X251800Y416600D01*
G01X277300Y108975D02*
Y109599D01*
X275299Y111600D01*
X271500D01*
G01X297821Y113961D02*
X294882Y116900D01*
X288234D01*
X285295Y113961D01*
G01X288116Y120306D02*
X285295D01*
G01X281300Y111475D02*
X278394D01*
X276169Y113700D01*
X275700D01*
X274950Y114450D01*
Y114627D01*
X274700Y114877D01*
Y118000D01*
X275775Y119075D01*
X277200D01*
G01X294800Y111800D02*
Y114300D01*
X293800Y115300D01*
X289100D01*
X288000Y114200D01*
Y111800D01*
X287011Y110811D01*
X285295D01*
G01Y131542D02*
X287796D01*
G01X290200Y129500D02*
X288299D01*
X287191Y128392D01*
X285295D01*
G01X288280Y126212D02*
Y124581D01*
X287155Y123456D01*
X285295D01*
G01X294600Y106900D02*
Y105800D01*
X295900Y104500D01*
Y101999D01*
X294301Y100400D01*
X292075D01*
G01X291380Y120306D02*
X288116D01*
G01X297821Y128012D02*
Y130078D01*
X296199Y131700D01*
X287954D01*
X287796Y131542D01*
G01X301936Y143897D02*
X300608D01*
X299618Y142907D01*
X297835D01*
G01X316066Y102743D02*
X315335Y102012D01*
X310768D01*
G01X304259Y106255D02*
X308502Y102012D01*
X310768D01*
G01X304000Y116500D02*
X304600D01*
X307300Y113800D01*
Y112300D01*
X308600Y111000D01*
X313000D01*
X313700Y110300D01*
Y106900D01*
X314707Y105893D01*
X316066D01*
G01X310661Y113961D02*
X313261D01*
X313262Y113960D01*
X316066D01*
G01X304259Y120306D02*
X306567Y117998D01*
X306585D01*
X307183Y117400D01*
X312200D01*
X314625Y119825D01*
X316700D01*
G01X320779Y111030D02*
X319559Y109810D01*
X318350D01*
X317350Y110810D01*
X316066D01*
G01X310661Y128012D02*
X311375Y128726D01*
Y134300D01*
G01X307560Y128500D02*
X306760Y129300D01*
X304400D01*
X303600Y130100D01*
Y132200D01*
G01D02*
X305200Y133800D01*
X307725D01*
X308225Y134300D01*
G01X308456Y273256D02*
X310356D01*
X310624Y272988D01*
X311995D01*
X313763Y274756D01*
G01X319859Y282404D02*
Y280852D01*
X313763Y274756D01*
G01X316118Y283191D02*
X313356D01*
X312272Y282107D01*
G01X305306Y285092D02*
X303908D01*
X302800Y286200D01*
G01X316118Y287128D02*
X313425D01*
X312114Y288439D01*
G01X320779Y111030D02*
X319243Y111666D01*
X318050Y112859D01*
Y117150D01*
X318000Y117200D01*
G01X327536Y285160D02*
X330016D01*
X331208Y286352D01*
X332174D01*
G01X327536Y283191D02*
X329997D01*
G01X327536Y287128D02*
X329129D01*
X331096Y289095D01*
X335516D01*
G54D25*
X18609Y422600D03*
X32191D03*
G54D16*
X24016Y89331D03*
X330315D03*
G54D118*
X317580Y67941D03*
Y73059D03*
X325020D03*
Y70500D03*
Y67941D03*
G54D52*
X47760Y226076D03*
Y235524D03*
X55240Y226076D03*
X51500D03*
X55240Y235524D03*
X297760Y320382D03*
Y330618D03*
X301500D03*
X305240Y320382D03*
Y330618D03*
G54D109*
X197012Y299320D03*
Y301880D03*
X210988D03*
Y299320D03*
G54D70*
X70354Y124261D03*
Y126230D03*
Y128198D03*
Y130167D03*
X81772D03*
Y128198D03*
Y126230D03*
Y124261D03*
X316118Y283191D03*
Y285160D03*
Y287128D03*
Y289097D03*
X327536Y285160D03*
Y283191D03*
Y289097D03*
Y287128D03*
G54D61*
X65945Y297776D03*
X73898Y24764D03*
X100472D03*
X127047D03*
X221142D03*
X247717D03*
G54D43*
X28255Y272190D03*
Y295220D03*
X83341Y87348D03*
Y110378D03*
X324605Y245210D03*
Y268240D03*
G54D34*
X33306Y196771D03*
Y195196D03*
Y193621D03*
Y192047D03*
Y201495D03*
Y199921D03*
Y198346D03*
G54D137*
G01X252342Y230595D02*
X253898Y232151D01*
G01X255492Y230595D02*
X257048Y232151D01*
G01X249193Y227446D02*
X250749Y229002D01*
G01X252342Y227446D02*
X253898Y229002D01*
G54D128*
G01X68898Y318544D02*
Y310902D01*
X69500Y310300D01*
Y308700D01*
G54D53*
X36414Y256051D03*
G54D26*
X22638Y27520D03*
X40354D03*
X269095Y29095D03*
X286811D03*
X313977Y27520D03*
X331693D03*
G54D71*
X72410Y141603D03*
X79890D03*
X72410Y149088D03*
X79890D03*
X144260Y209000D03*
X151740D03*
X318134Y300232D03*
Y307682D03*
X327760Y118500D03*
X325614Y300232D03*
Y307682D03*
X335240Y118500D03*
G54D80*
X107969Y63302D03*
Y66648D03*
X114661Y63302D03*
Y66648D03*
G54D119*
X329290Y126103D03*
X321416D03*
Y138309D03*
X329290D03*
X327322Y126103D03*
X325353D03*
X323384D03*
Y138309D03*
X325353D03*
X327322D03*
G54D35*
X20500Y211000D03*
X27500D03*
X20500Y218000D03*
X27500D03*
X25000Y240500D03*
X32000D03*
X25000Y233500D03*
X32000D03*
X207750Y361100D03*
X199750D03*
X207595Y378154D03*
X199595D03*
X203750Y369900D03*
X203595Y386954D03*
G54D44*
X26768Y258807D03*
G54D17*
X10470Y71500D03*
X12100Y438790D03*
X104000Y157600D03*
X269600Y337700D03*
X310800Y42000D03*
X323200Y451500D03*
G54D62*
X64567Y315493D03*
X146063D03*
G54D138*
G01X241314Y153187D02*
Y155497D01*
X240545Y157354D01*
X239744Y158155D01*
G01X242894Y227446D02*
X241338Y225890D01*
G01X239744Y227446D02*
X241300Y229002D01*
G01X239744Y233745D02*
X240594Y234595D01*
Y236872D01*
X239870Y237596D01*
G01X247225Y151675D02*
X246043Y152857D01*
Y155005D01*
G01Y158155D02*
X246857Y157341D01*
X247613Y155515D01*
Y153338D01*
G01X242894Y230595D02*
X244450Y232151D01*
G01X246043Y230595D02*
X247599Y232151D01*
G01X242894Y233745D02*
X242044Y234595D01*
Y236770D01*
X242870Y237596D01*
G54D129*
G01X20205Y255712D02*
X17065D01*
G01X62259Y197411D02*
Y191834D01*
X60400Y189975D01*
G01X166500Y96400D02*
Y98600D01*
X165440Y99660D01*
X161877D01*
G01X191538Y253411D02*
X190390Y254559D01*
Y260170D01*
X191583Y261363D01*
G01X193995Y260830D02*
X193785D01*
X193252Y261363D01*
X191583D01*
G01X199940Y117500D02*
X200800D01*
X203225Y119925D01*
X204000D01*
G01X215600Y316800D02*
X214959Y316159D01*
X210789D01*
G01X287608Y209084D02*
Y209085D01*
X286106Y210587D01*
G54D54*
X36414Y254083D03*
G54D90*
X126378Y105000D03*
Y122500D03*
G54D18*
X19500Y121603D03*
Y129083D03*
X18037Y311599D03*
Y304119D03*
X28000Y121603D03*
Y129083D03*
X34839Y311551D03*
Y304071D03*
X26438Y311575D03*
Y304095D03*
X36500Y121603D03*
X45000D03*
X36500Y129083D03*
X45000D03*
X43240Y311757D03*
Y304277D03*
X131000Y210260D03*
Y217740D03*
X220100Y80860D03*
Y88340D03*
X305320Y228803D03*
X313721Y228779D03*
X305320Y236283D03*
X313721Y236259D03*
X322122Y228755D03*
X330523Y228731D03*
X322122Y236235D03*
X330523Y236211D03*
X336500Y132260D03*
Y139740D03*
G54D27*
X27300Y68200D03*
X340639Y432809D03*
G54D72*
X71369Y163879D03*
X68810D03*
X66251D03*
Y172541D03*
X71369D03*
G54D81*
X98976Y415200D03*
X108424D03*
G54D36*
X24100Y226000D03*
X29900D03*
X40915Y225958D03*
X35115D03*
X112300Y112300D03*
X118100D03*
X112300Y118500D03*
X118100D03*
X112300Y128500D03*
X118100D03*
X253508Y263492D03*
X247708D03*
X291380Y138297D03*
X297180D03*
X294009Y147731D03*
X288209D03*
G54D45*
X23100Y264300D03*
X38101Y239700D03*
X108000Y237200D03*
G54D63*
G01X60864Y392075D02*
X59490Y393509D01*
X59500Y394000D01*
X60864Y344831D03*
Y360579D03*
Y357429D03*
Y354280D03*
Y351130D03*
Y347981D03*
Y376327D03*
Y373177D03*
Y370028D03*
Y366878D03*
Y363729D03*
Y388925D03*
Y385776D03*
Y382626D03*
Y379477D03*
Y392075D03*
X64014Y344831D03*
X67163D03*
X70313D03*
X73462D03*
X76612D03*
X64014Y360579D03*
X67163D03*
X70313D03*
X73462D03*
X76612D03*
X64014Y357429D03*
X67163D03*
X70313D03*
X73462D03*
X76612D03*
X64014Y354280D03*
X67163D03*
X70313D03*
X73462D03*
X76612D03*
X64014Y351130D03*
X67163D03*
X70313D03*
X73462D03*
X76612D03*
X64014Y347981D03*
X67163D03*
X70313D03*
X73462D03*
X76612D03*
X64014Y376327D03*
X67163D03*
X70313D03*
X73462D03*
X76612D03*
X64014Y373177D03*
X67163D03*
X70313D03*
X73462D03*
X76612D03*
X64014Y370028D03*
X67163D03*
X70313D03*
X73462D03*
X76612D03*
X64014Y366878D03*
X67163D03*
X70313D03*
X73462D03*
X76612D03*
X64014Y363729D03*
X67163D03*
X70313D03*
X73462D03*
X76612D03*
X64014Y388925D03*
X67163D03*
X70313D03*
X73462D03*
X76612D03*
X64014Y385776D03*
X67163D03*
X70313D03*
X73462D03*
X76612D03*
X64014Y382626D03*
X67163D03*
X70313D03*
X73462D03*
X76612D03*
X64014Y379477D03*
X67163D03*
X70313D03*
X73462D03*
X76612D03*
X64014Y392075D03*
X67163D03*
X70313D03*
X73462D03*
X76612D03*
X79762Y344831D03*
X82911D03*
X86061D03*
X89210D03*
X92360D03*
X79762Y360579D03*
X82911D03*
X86061D03*
X89210D03*
X92360D03*
X79762Y357429D03*
X82911D03*
X86061D03*
X89210D03*
X92360D03*
X79762Y354280D03*
X82911D03*
X86061D03*
X89210D03*
X92360D03*
X79762Y351130D03*
X82911D03*
X86061D03*
X89210D03*
X92360D03*
X79762Y347981D03*
X82911D03*
X86061D03*
X89210D03*
X92360D03*
X79762Y376327D03*
X82911D03*
X86061D03*
X89210D03*
X92360D03*
X79762Y373177D03*
X82911D03*
X86061D03*
X89210D03*
X92360D03*
X79762Y370028D03*
X82911D03*
X86061D03*
X89210D03*
X92360D03*
X79762Y366878D03*
X82911D03*
X86061D03*
X89210D03*
X92360D03*
X79762Y363729D03*
X82911D03*
X86061D03*
X89210D03*
X92360D03*
X79762Y388925D03*
X82911D03*
X86061D03*
X89210D03*
X92360D03*
X79762Y385776D03*
X82911D03*
X86061D03*
X89210D03*
X92360D03*
X79762Y382626D03*
X82911D03*
X86061D03*
X89210D03*
X92360D03*
X79762Y379477D03*
X82911D03*
X86061D03*
X89210D03*
X92360D03*
X79762Y392075D03*
X82911D03*
X86061D03*
X89210D03*
X92360D03*
X95510Y344831D03*
X98659D03*
X101809D03*
X104958D03*
X108108D03*
X95510Y360579D03*
X98659D03*
X101809D03*
X104958D03*
X108108D03*
X95510Y357429D03*
X98659D03*
X101809D03*
X104958D03*
X108108D03*
X95510Y354280D03*
X98659D03*
X101809D03*
X104958D03*
X108108D03*
X95510Y351130D03*
X98659D03*
X101809D03*
X104958D03*
X108108D03*
X95510Y347981D03*
X98659D03*
X101809D03*
X104958D03*
X108108D03*
X95510Y376327D03*
X98659D03*
X101809D03*
X104958D03*
X108108D03*
X95510Y373177D03*
X98659D03*
X101809D03*
X104958D03*
X108108D03*
X95510Y370028D03*
X98659D03*
X101809D03*
X104958D03*
X108108D03*
X95510Y366878D03*
X98659D03*
X101809D03*
X104958D03*
X108108D03*
X95510Y363729D03*
X98659D03*
X101809D03*
X104958D03*
X108108D03*
X95510Y388925D03*
X98659D03*
X101809D03*
X104958D03*
X108108D03*
X95510Y385776D03*
X98659D03*
X101809D03*
X104958D03*
X108108D03*
X95510Y382626D03*
X98659D03*
X101809D03*
X104958D03*
X108108D03*
X95510Y379477D03*
X98659D03*
X101809D03*
X104958D03*
X108108D03*
X95510Y392075D03*
X98659D03*
X101809D03*
X104958D03*
X108108D03*
X176752Y167603D03*
X179902D03*
X176752Y164454D03*
X179902D03*
X176752Y161304D03*
X179902D03*
X176752Y158155D03*
X179902D03*
X176752Y155005D03*
X179902D03*
X176752Y180202D03*
X179902D03*
X176752Y177052D03*
X179902D03*
X176752Y173903D03*
X179902D03*
X176752Y170753D03*
X179902D03*
X176752Y195950D03*
X179902D03*
X176752Y192800D03*
X179902D03*
X176752Y189651D03*
X179902D03*
X176752Y186501D03*
X179902D03*
X176752Y183351D03*
X179902D03*
X176752Y211698D03*
X179902D03*
X176752Y208548D03*
X179902D03*
X176752Y205399D03*
X179902D03*
X176752Y202249D03*
X179902D03*
X176752Y199099D03*
X179902D03*
X176752Y227446D03*
X179902D03*
X176752Y224296D03*
X179902D03*
X176752Y221147D03*
X179902D03*
X176752Y217997D03*
X179902D03*
X176752Y214847D03*
X179902D03*
X176752Y233745D03*
X179902D03*
X176752Y230595D03*
X179902D03*
X183051Y167603D03*
X186201D03*
X189350D03*
X192500D03*
X195650D03*
X183051Y164454D03*
X186201D03*
X189350D03*
X192500D03*
X195650D03*
X183051Y161304D03*
X186201D03*
X189350D03*
X192500D03*
X195650D03*
X183051Y158155D03*
X186201D03*
X189350D03*
X192500D03*
X195650D03*
X183051Y155005D03*
X186201D03*
X189350D03*
X192500D03*
X195650D03*
X183051Y180202D03*
X186201D03*
X189350D03*
X192500D03*
X183051Y177052D03*
X186201D03*
X189350D03*
X192500D03*
X183051Y173903D03*
X186201D03*
X189350D03*
X192500D03*
X183051Y170753D03*
X186201D03*
X189350D03*
X192500D03*
X195650D03*
X183051Y195950D03*
X186201D03*
X189350D03*
X192500D03*
X183051Y192800D03*
X186201D03*
X189350D03*
X192500D03*
X183051Y189651D03*
X186201D03*
X189350D03*
X192500D03*
X183051Y186501D03*
X186201D03*
X189350D03*
X192500D03*
X183051Y183351D03*
X186201D03*
X189350D03*
X192500D03*
X183051Y211698D03*
X186201D03*
X189350D03*
X192500D03*
X183051Y208548D03*
X186201D03*
X189350D03*
X192500D03*
X183051Y205399D03*
X186201D03*
X189350D03*
X192500D03*
X183051Y202249D03*
X186201D03*
X189350D03*
X192500D03*
X183051Y199099D03*
X186201D03*
X189350D03*
X192500D03*
X183051Y227446D03*
X186201D03*
X189350D03*
X192500D03*
X195650D03*
X183051Y224296D03*
X186201D03*
X189350D03*
X192500D03*
X195650D03*
X183051Y221147D03*
X186201D03*
X189350D03*
X192500D03*
X195650D03*
X183051Y217997D03*
X186201D03*
X189350D03*
X192500D03*
X195650D03*
X183051Y214847D03*
X186201D03*
X189350D03*
X192500D03*
X183051Y233745D03*
X186201D03*
X189350D03*
X192500D03*
X195650D03*
X183051Y230595D03*
X186201D03*
X189350D03*
X192500D03*
X195650D03*
X198799Y167603D03*
X201949D03*
X205098D03*
X208248D03*
X211398D03*
X198799Y164454D03*
X201949D03*
X205098D03*
X208248D03*
X211398D03*
X198799Y161304D03*
X201949D03*
X205098D03*
X208248D03*
X211398D03*
X198799Y158155D03*
X201949D03*
X205098D03*
X208248D03*
X211398D03*
X198799Y155005D03*
X201949D03*
X205098D03*
X208248D03*
X211398D03*
X198799Y180202D03*
X201949D03*
X205098D03*
X208248D03*
X211398D03*
X198799Y177052D03*
X201949D03*
X205098D03*
X208248D03*
X211398D03*
X198799Y170753D03*
X201949D03*
X205098D03*
X208248D03*
X211398D03*
X198799Y195950D03*
X201949D03*
X205098D03*
X208248D03*
X211398D03*
X198799Y192800D03*
X201949D03*
X205098D03*
X208248D03*
X211398D03*
X198799Y189651D03*
X201949D03*
X205098D03*
X208248D03*
X211398D03*
X198799Y186501D03*
X201949D03*
X205098D03*
X208248D03*
X211398D03*
X198799Y183351D03*
X201949D03*
X205098D03*
X208248D03*
X211398D03*
X198799Y211698D03*
X201949D03*
X205098D03*
X208248D03*
X211398D03*
X198799Y208548D03*
X201949D03*
X205098D03*
X208248D03*
X211398D03*
X198799Y205399D03*
X201949D03*
X205098D03*
X208248D03*
X211398D03*
X198799Y202249D03*
X201949D03*
X205098D03*
X208248D03*
X211398D03*
X198799Y199099D03*
X201949D03*
X205098D03*
X208248D03*
X211398D03*
X198799Y227446D03*
X201949D03*
X205098D03*
X208248D03*
X211398D03*
X198799Y224296D03*
X201949D03*
X205098D03*
X208248D03*
X211398D03*
X198799Y221147D03*
X201949D03*
X205098D03*
X208248D03*
X211398D03*
X198799Y217997D03*
X201949D03*
X205098D03*
X208248D03*
X211398D03*
X198799Y233745D03*
X201949D03*
X205098D03*
X208248D03*
X211398D03*
X198799Y230595D03*
X201949D03*
X205098D03*
X208248D03*
X211398D03*
X214547Y167603D03*
X217697D03*
X220846D03*
X223996D03*
X227146D03*
X214547Y164454D03*
X217697D03*
X220846D03*
X223996D03*
X227146D03*
X214547Y161304D03*
X217697D03*
X220846D03*
X223996D03*
X227146D03*
X214547Y158155D03*
X217697D03*
X220846D03*
X223996D03*
X227146D03*
X214547Y155005D03*
X217697D03*
X220846D03*
X223996D03*
X227146D03*
X214547Y180202D03*
X217697D03*
X220846D03*
X223996D03*
X227146D03*
X214547Y177052D03*
X217697D03*
X220846D03*
X223996D03*
X227146D03*
X214547Y170753D03*
X217697D03*
X220846D03*
X223996D03*
X227146D03*
X214547Y195950D03*
X217697D03*
X220846D03*
X223996D03*
X227146D03*
X214547Y192800D03*
X217697D03*
X220846D03*
X223996D03*
X227146D03*
X214547Y189651D03*
X217697D03*
X220846D03*
X223996D03*
X227146D03*
X214547Y186501D03*
X217697D03*
X220846D03*
X223996D03*
X227146D03*
X214547Y183351D03*
X217697D03*
X220846D03*
X223996D03*
X227146D03*
X214547Y211698D03*
X217697D03*
X220846D03*
X223996D03*
X227146D03*
X214547Y208548D03*
X217697D03*
X220846D03*
X223996D03*
X227146D03*
X214547Y205399D03*
X217697D03*
X220846D03*
X223996D03*
X227146D03*
X214547Y202249D03*
X217697D03*
X220846D03*
X223996D03*
X227146D03*
X214547Y199099D03*
X217697D03*
X220846D03*
X223996D03*
X227146D03*
X214547Y227446D03*
X217697D03*
X220846D03*
X223996D03*
X227146D03*
X214547Y224296D03*
X217697D03*
X220846D03*
X223996D03*
X227146D03*
X214547Y221147D03*
X217697D03*
X220846D03*
X223996D03*
X227146D03*
X214547Y217997D03*
X217697D03*
X220846D03*
X223996D03*
X227146D03*
X214547Y233745D03*
X217697D03*
X220846D03*
X223996D03*
X227146D03*
X214547Y230595D03*
X217697D03*
X220846D03*
X223996D03*
X227146D03*
X230295Y167603D03*
X233445D03*
X236594D03*
X239744D03*
X230295Y164454D03*
X233445D03*
X236594D03*
X239744D03*
X230295Y161304D03*
X233445D03*
X236594D03*
X239744D03*
X230295Y158155D03*
X233445D03*
X236594D03*
X239744D03*
X230295Y155005D03*
X233445D03*
X236594D03*
X239744D03*
X230295Y180202D03*
X233445D03*
X239744D03*
X230295Y177052D03*
X233445D03*
X239744D03*
Y173903D03*
X230295Y170753D03*
X233445D03*
X236594D03*
X239744D03*
X230295Y195950D03*
X233445D03*
X239744D03*
X230295Y192800D03*
X233445D03*
X239744D03*
X230295Y189651D03*
X233445D03*
X239744D03*
X230295Y186501D03*
X233445D03*
X239744D03*
X230295Y183351D03*
X233445D03*
X239744D03*
X230295Y211698D03*
X233445D03*
X239744D03*
X230295Y208548D03*
X233445D03*
X239744D03*
X230295Y205399D03*
X233445D03*
X239744D03*
X230295Y202249D03*
X233445D03*
X239744D03*
X230295Y199099D03*
X233445D03*
X239744D03*
X230295Y227446D03*
X233445D03*
X236594D03*
X239744D03*
X230295Y224296D03*
X233445D03*
X236594D03*
X239744D03*
X230295Y221147D03*
X233445D03*
X236594D03*
X239744D03*
X230295Y217997D03*
X233445D03*
X236594D03*
X239744D03*
Y214847D03*
X230295Y233745D03*
X233445D03*
X236594D03*
X239744D03*
X230295Y230595D03*
X233445D03*
X236594D03*
X239744D03*
X242894Y167603D03*
X246043D03*
X249193D03*
X252342D03*
X255492D03*
X242894Y164454D03*
X246043D03*
X249193D03*
X252342D03*
X255492D03*
X242894Y161304D03*
X246043D03*
X249193D03*
X252342D03*
X255492D03*
X242894Y158155D03*
X246043D03*
X249193D03*
X252342D03*
X255492D03*
X242894Y155005D03*
X246043D03*
X249193D03*
X252342D03*
X255492D03*
X242894Y180202D03*
X246043D03*
X249193D03*
X252342D03*
X255492D03*
X242894Y177052D03*
X246043D03*
X249193D03*
X252342D03*
X255492D03*
X242894Y173903D03*
X246043D03*
X249193D03*
X252342D03*
X255492D03*
X242894Y170753D03*
X246043D03*
X249193D03*
X252342D03*
X255492D03*
X242894Y195950D03*
X246043D03*
X249193D03*
X252342D03*
X255492D03*
X242894Y192800D03*
X246043D03*
X249193D03*
X252342D03*
X255492D03*
X242894Y189651D03*
X246043D03*
X249193D03*
X252342D03*
X255492D03*
X242894Y186501D03*
X246043D03*
X249193D03*
X252342D03*
X255492D03*
X242894Y183351D03*
X246043D03*
X249193D03*
X252342D03*
X255492D03*
X242894Y211698D03*
X246043D03*
X249193D03*
X252342D03*
X255492D03*
X242894Y208548D03*
X246043D03*
X249193D03*
X252342D03*
X255492D03*
X242894Y205399D03*
X246043D03*
X249193D03*
X252342D03*
X255492D03*
X242894Y202249D03*
X246043D03*
X249193D03*
X252342D03*
X255492D03*
X242894Y199099D03*
X246043D03*
X249193D03*
X252342D03*
X255492D03*
X242894Y227446D03*
X246043D03*
X249193D03*
X252342D03*
X255492D03*
X242894Y224296D03*
X246043D03*
X249193D03*
X252342D03*
X255492D03*
X242894Y221147D03*
X246043D03*
X249193D03*
X252342D03*
X255492D03*
X242894Y217997D03*
X246043D03*
X249193D03*
X252342D03*
X255492D03*
X242894Y214847D03*
X246043D03*
X249193D03*
X252342D03*
X255492D03*
X242894Y233745D03*
X246043D03*
X249193D03*
X252342D03*
X255492D03*
X242894Y230595D03*
X246043D03*
X249193D03*
X252342D03*
X255492D03*
G54D139*
G01X-26000Y418816D02*
Y406794D01*
X-25188Y405982D01*
X-20391D01*
X-16200Y401791D01*
Y395573D01*
X-20391Y391382D01*
X-37400D01*
X-38750Y390032D01*
Y387832D01*
X-37400Y386482D01*
X-20391D01*
X-16200Y382291D01*
Y376073D01*
X-20391Y371882D01*
X-39600D01*
X-40950Y370532D01*
Y368332D01*
X-39600Y366982D01*
X-20391D01*
X-16200Y362791D01*
Y356573D01*
X-20391Y352382D01*
X-39600D01*
X-40950Y351032D01*
Y348832D01*
X-39600Y347482D01*
X-20391D01*
X-16200Y343291D01*
Y337073D01*
X-20391Y332882D01*
X-39600D01*
X-40950Y331532D01*
Y329332D01*
X-39600Y327982D01*
X-20391D01*
X-16200Y323791D01*
Y317573D01*
X-20391Y313382D01*
X-36450D01*
X-37800Y314732D01*
Y316882D01*
X-36450Y318232D01*
X-22400D01*
X-21050Y319582D01*
Y321782D01*
X-22400Y323132D01*
X-41609D01*
X-45800Y327323D01*
Y333541D01*
X-41609Y337732D01*
X-22400D01*
X-21050Y339082D01*
Y341282D01*
X-22400Y342632D01*
X-41609D01*
X-45800Y346823D01*
Y353041D01*
X-41609Y357232D01*
X-22400D01*
X-21050Y358582D01*
Y360782D01*
X-22400Y362132D01*
X-41609D01*
X-45800Y366323D01*
Y372541D01*
X-41609Y376732D01*
X-22400D01*
X-21050Y378082D01*
Y380282D01*
X-22400Y381632D01*
X-39409D01*
X-43600Y385823D01*
Y392041D01*
X-39409Y396232D01*
X-22400D01*
X-21050Y397582D01*
Y399782D01*
X-22400Y401132D01*
X-35146D01*
X-36000Y401986D01*
Y418816D01*
G01X25600Y106300D02*
X16800D01*
X12500Y102000D01*
G01X16825Y328600D02*
Y335435D01*
X15850Y336410D01*
Y415418D01*
X12770Y418498D01*
Y424270D01*
X13500Y425000D01*
X14700D01*
G01X16825Y328600D02*
X22225Y334000D01*
X27269D01*
X31269Y338000D01*
X34925D01*
G01X23810Y322534D02*
X23776Y322500D01*
X17500D01*
X17000Y322000D01*
Y320075D01*
G01Y316925D02*
X17850D01*
X21000Y320075D01*
G01X38075Y338000D02*
Y341925D01*
X37500Y342500D01*
X34500D01*
X32500Y340500D01*
X30000D01*
X26100Y344400D01*
X17910D01*
X17410Y344900D01*
Y416066D01*
X14600Y418876D01*
Y422500D01*
G01X45276Y89000D02*
X39200D01*
X38700Y89500D01*
Y99600D01*
X32000Y106300D01*
X25600D01*
G01X44470Y266975D02*
X42975D01*
X41800Y265800D01*
Y264800D01*
X37915Y260915D01*
X33715D01*
X32673Y259873D01*
Y258413D01*
G01X28260Y327559D02*
Y330859D01*
X29801Y332400D01*
X36400D01*
X37500Y333500D01*
Y335500D01*
X37984Y335984D01*
Y337909D01*
X38075Y338000D01*
G01X21000Y320075D02*
X21525Y320600D01*
X23924D01*
X25445Y321230D01*
X26729D01*
X27940Y322441D01*
X28260D01*
G01X44700Y428925D02*
Y429025D01*
X41725Y432000D01*
X36700D01*
X33900Y434800D01*
X28000D01*
X27143Y433943D01*
Y422143D01*
X18970Y413970D01*
Y357500D01*
X21470Y355000D01*
X30500D01*
X33000Y352500D01*
Y344500D01*
X31000Y342500D01*
G01X40500Y374075D02*
X39480Y373055D01*
X32956D01*
X31100Y371199D01*
Y366411D01*
X23843Y359154D01*
X23819D01*
G01X26300Y374400D02*
X31000D01*
X40200Y383600D01*
X42195D01*
X42695Y384100D01*
Y384759D01*
X43836Y385900D01*
G01X40500Y392425D02*
X39276D01*
X38601Y393100D01*
X37241D01*
X36659Y392859D01*
X32700Y388900D01*
X27853D01*
X27599Y389154D01*
X23819D01*
G01X40500Y385425D02*
X40075Y385000D01*
X39400D01*
X37840Y383440D01*
X34342D01*
X31600Y380698D01*
Y379600D01*
G01X40500Y388575D02*
X34376D01*
X33301Y387500D01*
X29401D01*
X27200Y385299D01*
Y382535D01*
X23819Y379154D01*
G01X40500Y402575D02*
X37876D01*
X34455Y399154D01*
X23819D01*
G01X40354Y27520D02*
X40401Y27567D01*
Y32153D01*
X40075Y32479D01*
Y38000D01*
G01X46984Y37909D02*
X44759Y35684D01*
X42391D01*
X40075Y38000D01*
G01X46984Y37909D02*
Y36286D01*
X48397Y34873D01*
X50641D01*
G01X47075Y38000D02*
X46984Y37909D01*
G01X50641Y34873D02*
X48776Y36738D01*
Y40868D01*
X45479Y44165D01*
Y45897D01*
G01X50710Y54724D02*
Y54089D01*
X49518Y52897D01*
X48038D01*
G01X53600Y44100D02*
X52600Y45100D01*
Y57994D01*
X51236Y59358D01*
X48656D01*
X47676Y60338D01*
X38150D01*
X37488Y61000D01*
Y72240D01*
X37988Y72740D01*
X39861D01*
X40361Y72240D01*
X41941D01*
G01X62321Y69200D02*
Y67600D01*
X55632Y60911D01*
X50908D01*
X47059Y64760D01*
G01X52500Y73075D02*
X50575Y75000D01*
X45000D01*
X44500Y74500D01*
Y72240D01*
G01X52500Y62925D02*
X48303Y67122D01*
X45336D01*
X44500Y66286D01*
Y64760D01*
G01X45001Y95144D02*
X57064D01*
X63921Y88287D01*
Y74719D01*
X67715Y70925D01*
X86776D01*
X88716Y68985D01*
X90151D01*
G01X40940Y112559D02*
Y110120D01*
X42060Y109000D01*
X45276D01*
G01X42281Y203183D02*
X46307D01*
G01X33306Y201495D02*
X34746D01*
X35471Y202220D01*
X40203D01*
X41166Y203183D01*
X42281D01*
G01X46307D02*
X47675D01*
X47958Y202900D01*
X50270D01*
X50553Y203183D01*
X51849D01*
G01X42409Y214718D02*
Y210701D01*
G01X33306Y203464D02*
X34364D01*
X35400Y204500D01*
Y207700D01*
X36292Y208592D01*
G01D02*
X36870Y209170D01*
X40659D01*
X42190Y210701D01*
X42409D01*
G01X47760Y226076D02*
Y218123D01*
X48023Y217860D01*
G01X39800Y213800D02*
X40718Y214718D01*
X42409D01*
G01X36875Y214700D02*
X37775Y213800D01*
X39800D01*
G01X33725Y214700D02*
Y216025D01*
X35700Y218000D01*
G01X41100Y248900D02*
X35463D01*
X34642Y249721D01*
Y251327D01*
G01X44325Y248800D02*
X44225Y248900D01*
X41100D01*
G01X43525Y244900D02*
X44325Y245700D01*
Y248800D01*
G01X55240Y243700D02*
Y246860D01*
X54325Y247775D01*
X50736D01*
X49711Y248800D01*
X47475D01*
G01X46675Y244900D02*
X47700D01*
X49700Y242900D01*
G01X44470Y266975D02*
X46350D01*
X48725Y264600D01*
G01X46220Y277170D02*
X48820Y274570D01*
Y269571D01*
X51875Y266516D01*
Y264600D01*
G01X46925Y324000D02*
X44525D01*
G01X46925Y336000D02*
Y335424D01*
X45581Y334080D01*
X43338D01*
X42370Y333112D01*
Y326407D01*
X42695Y326082D01*
Y323241D01*
X43766Y322170D01*
X44812D01*
X47296Y319686D01*
X49736D01*
X49950Y319900D01*
X52400D01*
X54300Y318000D01*
Y316600D01*
X56800Y314100D01*
Y285800D01*
X55200Y284200D01*
Y271284D01*
X58800Y267684D01*
Y265000D01*
G01X46925Y340000D02*
Y339874D01*
X40810Y333759D01*
Y325760D01*
X41135Y325435D01*
Y322594D01*
X43119Y320610D01*
X44165D01*
X46649Y318126D01*
X48174D01*
X52700Y313600D01*
Y308500D01*
X55200Y306000D01*
Y286600D01*
X53400Y284800D01*
Y270876D01*
X56400Y267876D01*
Y257057D01*
X56000Y256091D01*
Y252576D01*
X57621Y250955D01*
Y233579D01*
X59300Y231900D01*
Y223900D01*
X66335Y216865D01*
Y213678D01*
X73071Y206942D01*
X77442D01*
X79500Y209000D01*
X81400D01*
X85140Y205260D01*
Y193300D01*
X82652Y190812D01*
X80788D01*
G01X46925Y328000D02*
X45241D01*
X44481Y328760D01*
G01X38560Y329739D02*
X36380Y327559D01*
X35740D01*
G01X38560Y329739D02*
Y331715D01*
X39100Y332255D01*
Y334600D01*
X40500Y336000D01*
Y345925D01*
X37925Y348500D01*
G01X39975Y317100D02*
X43500D01*
G01X36825D02*
Y318376D01*
X34600Y320601D01*
Y321800D01*
X35241Y322441D01*
X35740D01*
G01X46925Y344000D02*
Y342860D01*
X46235Y342170D01*
X45382D01*
X44220Y341008D01*
G01X37400Y359900D02*
X37525D01*
X40500Y356925D01*
G01Y363925D02*
Y360075D01*
G01X47500Y351925D02*
Y348575D01*
X46925Y348000D01*
G01Y360000D02*
X44525D01*
G01X37925Y352000D02*
X37525Y352400D01*
X35100D01*
G01X41075Y348500D02*
X38017Y351558D01*
Y351908D01*
X37925Y352000D01*
G01X35900Y363025D02*
X39600D01*
X40500Y363925D01*
G01Y370925D02*
X38100D01*
X37800Y371225D01*
G01X46925Y372000D02*
X44400D01*
X41400Y369000D01*
X36800D01*
X36200Y368400D01*
G01X46925Y368000D02*
Y364000D01*
G01X60864Y376327D02*
X59673D01*
X57000Y379000D01*
Y380671D01*
X51771Y385900D01*
X43836D01*
G01X58620Y408779D02*
X54241Y404400D01*
X44170D01*
X42470Y402700D01*
Y387266D01*
X43836Y385900D01*
G01X46925Y384000D02*
X44525D01*
G01X46925Y376000D02*
X44525D01*
G01X47075Y391730D02*
X50075Y388730D01*
Y387700D01*
G01X46925Y380000D02*
X44500D01*
G01X40500Y381075D02*
X43425D01*
X44500Y380000D01*
G01X47325Y394350D02*
X47125Y394150D01*
X44525D01*
G01X40500Y395575D02*
X38576D01*
X37916Y394915D01*
X36911D01*
G01X40500Y399425D02*
X38155D01*
X37067Y398337D01*
G01X50475Y397850D02*
Y399225D01*
X50112Y399588D01*
X49087D01*
X47325Y401350D01*
G01X44330Y401450D02*
X47225D01*
X47325Y401350D01*
G01X79000Y406075D02*
X77871D01*
X76030Y407916D01*
Y410600D01*
X75480Y411150D01*
X54760D01*
X52710Y409100D01*
X39530D01*
G01X44575Y419700D02*
X43600Y420675D01*
Y422800D01*
G01X46100Y412700D02*
X44575Y414225D01*
Y415700D01*
G01X51823Y418655D02*
X50055D01*
X49200Y417800D01*
Y414200D01*
X47700Y412700D01*
X46100D01*
G01X41425Y415700D02*
Y419700D01*
G01D02*
Y421469D01*
X41000Y421894D01*
Y423225D01*
X40800Y423425D01*
G01D02*
X40700Y423525D01*
X39975D01*
X38000Y425500D01*
Y428800D01*
G01X44700Y428925D02*
X44792Y429017D01*
X48508D01*
X48600Y428925D01*
G01X44700Y432075D02*
Y433800D01*
X45100Y434200D01*
Y435800D01*
G01X56348Y36210D02*
X55128D01*
X53791Y34873D01*
G01X63086Y65762D02*
Y61675D01*
X70443Y54318D01*
Y37317D01*
X81060Y26700D01*
Y22840D01*
X85700Y18200D01*
X188200D01*
X207700Y37700D01*
Y49600D01*
X192200Y65100D01*
X186700D01*
X183600Y68200D01*
Y80200D01*
X180600Y83200D01*
Y85700D01*
X177900Y88400D01*
Y94200D01*
X179900Y96200D01*
Y99900D01*
X183000Y103000D01*
Y107778D01*
X178184Y112594D01*
Y115416D01*
X175729Y117871D01*
X167029D01*
X166400Y118500D01*
Y123800D01*
X166901Y124301D01*
Y124304D01*
X167329Y124732D01*
X169324D01*
X170393Y125801D01*
X170861Y126929D01*
Y128205D01*
X170867Y128211D01*
G01X52500Y62925D02*
X54923D01*
X59240Y67242D01*
G01X52502Y80978D02*
X61821D01*
X62321Y80478D01*
Y69200D01*
G01X52120Y78373D02*
Y75085D01*
X52500Y74705D01*
Y73075D01*
G01X63918Y123080D02*
Y121768D01*
X59945Y117795D01*
G01D02*
X58040Y119700D01*
Y121685D01*
X56300Y123425D01*
Y134830D01*
X58028Y136558D01*
X60358D01*
X60800Y137000D01*
G01X60090Y123085D02*
X59945Y122940D01*
Y120630D01*
G01X60800Y137000D02*
Y137900D01*
X59441Y139259D01*
Y141011D01*
G01X62000Y148589D02*
X62400Y148989D01*
Y166500D01*
X63200Y167300D01*
X68000D01*
X69540Y168840D01*
Y172720D01*
X68960Y173300D01*
G01X52410Y186900D02*
X55230Y189720D01*
Y194030D01*
X57141Y195941D01*
Y197411D01*
G01X62259Y204989D02*
Y211100D01*
G01D02*
Y212840D01*
X61568Y213531D01*
X58823D01*
G01X54975Y215900D02*
Y213256D01*
X54633Y212914D01*
Y211292D01*
X54725Y211200D01*
G01D02*
X56355D01*
X56555Y211400D01*
X57800D01*
X59700Y209500D01*
Y204989D01*
G01X51825Y220600D02*
X51500Y220925D01*
Y226076D01*
G01X51825Y220600D02*
X54085Y222860D01*
X57040D01*
X57500Y223320D01*
Y229940D01*
X54960Y232480D01*
X53700D01*
X53096Y233084D01*
Y239704D01*
X51600Y241200D01*
G01X61216Y225725D02*
X63341Y223600D01*
X68270D01*
X70289Y225619D01*
Y227521D01*
G01X54975Y220600D02*
Y215900D01*
G01X58800Y265000D02*
Y258772D01*
X57560Y255779D01*
Y253223D01*
X59181Y251602D01*
Y236499D01*
X59850Y235830D01*
G01X61216Y228875D02*
Y232295D01*
X62520Y233599D01*
Y233600D01*
G01X60741Y241363D02*
Y237569D01*
X62520Y235790D01*
Y233600D01*
G01X55240Y235524D02*
Y243700D01*
G01X71100Y233575D02*
X70968Y233629D01*
X68930Y238548D01*
Y243170D01*
X67100Y245000D01*
X61500D01*
X60741Y245759D01*
Y249237D01*
G01D02*
Y257770D01*
X61500Y258529D01*
Y262301D01*
X63799Y264600D01*
X72800D01*
X76470Y260930D01*
X80970D01*
X81600Y260300D01*
Y258032D01*
X84941Y254691D01*
Y249237D01*
G01X48725Y260800D02*
Y264600D01*
G01X107400Y270325D02*
Y270043D01*
X104880Y267523D01*
X104263Y266035D01*
X102928Y264700D01*
X100300D01*
X98700Y266300D01*
X95041D01*
X93811Y265070D01*
X79216D01*
X78636Y265650D01*
X78283D01*
X76213Y267720D01*
X63180D01*
X58900Y272000D01*
Y283000D01*
X62900Y287000D01*
Y293500D01*
X60617Y295783D01*
Y312008D01*
X60613Y312012D01*
G01X111500Y267925D02*
X106835D01*
X105967Y267057D01*
X105369Y265613D01*
X103356Y263600D01*
X99800D01*
X98200Y265200D01*
X96149D01*
X94959Y264010D01*
X78776D01*
X78196Y264590D01*
X77842D01*
X76272Y266160D01*
X62532D01*
X57100Y271592D01*
Y283600D01*
X61200Y287700D01*
Y292500D01*
X58700Y295000D01*
Y316100D01*
X60600Y318000D01*
G01X61200Y279975D02*
Y282600D01*
G01D02*
X64500Y285900D01*
Y291400D01*
X66600Y293500D01*
X67900D01*
X70600Y296200D01*
Y306400D01*
X71700Y307500D01*
Y310200D01*
X70400Y311500D01*
Y315400D01*
X70866Y315866D01*
Y318544D01*
G01X55800Y331075D02*
Y331434D01*
X60225Y335859D01*
Y336099D01*
G01X64900Y327925D02*
X63000Y326025D01*
Y324100D01*
G01X55800Y327925D02*
X57054D01*
X57515Y328386D01*
Y330716D01*
X63140Y336341D01*
Y339239D01*
X67163Y343262D01*
Y344831D01*
G01X50075Y324000D02*
Y325176D01*
X53000Y328101D01*
Y332799D01*
X54271Y334070D01*
X56229D01*
X57300Y335141D01*
Y338940D01*
X59760Y341400D01*
X62900D01*
X65607Y344107D01*
Y346425D01*
X67163Y347981D01*
G01X61000Y331075D02*
Y331299D01*
X64800Y335099D01*
Y338500D01*
X70313Y344013D01*
Y344831D01*
G01X50075Y328000D02*
Y332000D01*
G01X68800Y328225D02*
X65500Y324925D01*
Y323899D01*
X63701Y322100D01*
X61100D01*
X57000Y318000D01*
X56600D01*
G01X52820Y325200D02*
X53820Y326200D01*
X60390D01*
X61000Y326810D01*
Y327925D01*
G01X57400Y345400D02*
Y346681D01*
X60293Y349574D01*
X62458D01*
X64014Y351130D01*
G01Y344831D02*
X62458Y343275D01*
G01X50075Y332000D02*
Y333276D01*
X52766Y335967D01*
Y338567D01*
X56999Y342800D01*
X57600D01*
X59334Y344534D01*
Y346451D01*
X60864Y347981D01*
G01X50075Y344000D02*
X52800Y346725D01*
Y347499D01*
X56834Y351533D01*
Y355510D01*
X58753Y357429D01*
X60864D01*
G01X50075Y336000D02*
X51706Y337631D01*
Y339405D01*
X53560Y341259D01*
Y343778D01*
X55460Y345678D01*
Y346160D01*
X59555Y350255D01*
X60864Y351130D01*
G01X50075Y340000D02*
X52500Y342425D01*
Y344218D01*
X54360Y346078D01*
Y346790D01*
X60294Y352724D01*
X62458D01*
X64014Y354280D01*
G01Y357429D02*
X62458Y355873D01*
G01X60864Y354280D02*
X58564D01*
G01X50075Y348000D02*
Y350976D01*
X58122Y359023D01*
X62458D01*
X64014Y360579D01*
G01X50075Y384000D02*
X51845Y382230D01*
X53234D01*
X55700Y379764D01*
Y378601D01*
X59568Y374733D01*
X62458D01*
X64014Y373177D01*
G01X60864Y370028D02*
X61850D01*
X63380Y368498D01*
X109302D01*
X110010Y367790D01*
X116110D01*
X119230Y364670D01*
X122330D01*
G01X60864Y363729D02*
X56472D01*
X52000Y368201D01*
Y370075D01*
X50075Y372000D01*
G01X64014Y366878D02*
X63028D01*
X61498Y368408D01*
X60008D01*
X59100Y367500D01*
X54801D01*
X53300Y369001D01*
Y371511D01*
X50075Y374736D01*
Y376000D01*
G01Y368000D02*
X52475Y365600D01*
Y364000D01*
G01X50075Y380000D02*
X52000D01*
X59334Y372666D01*
Y372543D01*
X60230Y371647D01*
X60353D01*
X60416Y371584D01*
X62458D01*
X64014Y370028D01*
G01X63000Y402925D02*
Y401294D01*
X57426Y395720D01*
Y392363D01*
X60864Y388925D01*
G01X50475Y394350D02*
X51149D01*
X57800Y387699D01*
Y384469D01*
X59643Y382626D01*
X60864D01*
G01X50075Y387700D02*
X52362D01*
X58996Y381066D01*
X62425D01*
X64014Y379477D01*
G01Y382626D02*
X62400Y384240D01*
Y386870D01*
X61900Y387370D01*
X60230D01*
X55400Y392200D01*
Y399500D01*
X53550Y401350D01*
X50475D01*
G01X63000Y406075D02*
Y408400D01*
X63200Y408600D01*
G01X59303Y416096D02*
X68695D01*
X69599Y417000D01*
X70589D01*
X70889Y417300D01*
X74419D01*
G01X50700Y439100D02*
X50200Y438600D01*
Y435306D01*
X48600Y433706D01*
Y432075D01*
G01X61201Y465590D02*
Y451901D01*
X60100Y450800D01*
Y448500D01*
X50700Y439100D01*
G01X58839Y465590D02*
X58912Y465517D01*
Y451313D01*
X58400Y450801D01*
Y448974D01*
X57026Y447600D01*
X56500D01*
G01X72500Y66500D02*
Y62556D01*
X80308Y54748D01*
Y41562D01*
X83560Y38310D01*
Y23240D01*
X87040Y19760D01*
X187553D01*
X206140Y38347D01*
Y48953D01*
X191553Y63540D01*
X186053D01*
X182000Y67593D01*
Y78900D01*
X179040Y81860D01*
Y85053D01*
X176340Y87753D01*
Y94847D01*
X178300Y96807D01*
Y100800D01*
X181000Y103500D01*
Y107320D01*
X176488Y111832D01*
Y114712D01*
X174889Y116311D01*
X166029D01*
X164840Y117500D01*
Y119485D01*
X164400Y119925D01*
G01X64559Y148589D02*
Y150341D01*
X63961Y150939D01*
Y157632D01*
X65223Y158894D01*
X68294D01*
X68600Y159200D01*
Y159160D01*
G01X76442Y166907D02*
Y170043D01*
X80599Y174200D01*
X90353D01*
X98183Y166370D01*
X121630D01*
X127300Y160700D01*
X139700D01*
X143525Y164525D01*
X148400D01*
G01X81500Y167325D02*
X79505Y165330D01*
X77776D01*
X77523Y165077D01*
X74577D01*
X73200Y163700D01*
Y161900D01*
X72600Y161300D01*
X70000D01*
X68810Y162490D01*
Y163879D01*
G01X69200Y183875D02*
Y183599D01*
X71199Y181600D01*
X72201D01*
X72800Y181001D01*
Y180725D01*
G01X106600Y253689D02*
X104173Y251262D01*
Y243027D01*
X105800Y241400D01*
Y234910D01*
X88260Y217370D01*
Y188053D01*
X83547Y183340D01*
X80639D01*
X76269Y178970D01*
X74525D01*
X72800Y180695D01*
Y180725D01*
G01X97316Y239985D02*
Y238517D01*
X96400Y237601D01*
Y231900D01*
X86700Y222200D01*
Y188700D01*
X82900Y184900D01*
X79384D01*
X75284Y180800D01*
G01X76000Y175100D02*
X74400Y176700D01*
X70220D01*
X69200Y177720D01*
Y180725D01*
G01X76000Y175100D02*
Y172100D01*
X74300Y170400D01*
X72600D01*
X71369Y171631D01*
Y172541D01*
G01X73400Y219625D02*
X68770Y214995D01*
Y213450D01*
X70720Y211500D01*
X80170D01*
X81000Y212330D01*
G01X75400Y229825D02*
Y227847D01*
X70453Y222900D01*
G01X77500Y219625D02*
Y217774D01*
X77040Y217314D01*
X74583D01*
G01X81500Y222775D02*
X77500D01*
G01X65216Y225725D02*
X66838D01*
X67700Y226587D01*
Y229725D01*
G01X73400Y222775D02*
X82725Y232100D01*
X84941D01*
G01X76200Y247400D02*
X77384Y246216D01*
Y240085D01*
G01X80200Y234100D02*
X79075Y232975D01*
X75400D01*
G01X75416Y240085D02*
Y238194D01*
X76560Y237050D01*
X77250D01*
X80200Y234100D01*
G01X65216Y228875D02*
Y230486D01*
X67699Y232969D01*
Y235380D01*
G01X65859Y241363D02*
Y237220D01*
X67699Y235380D01*
G01X70289Y227521D02*
X73447Y230679D01*
Y233948D01*
X74300Y234801D01*
Y237099D01*
X73447Y237952D01*
Y240085D01*
G01X77010Y256645D02*
X75416Y255051D01*
Y250715D01*
G01X79575Y259200D02*
Y257876D01*
X78344Y256645D01*
X77010D01*
G01X77384Y253769D02*
Y250715D01*
G01X99284Y250615D02*
Y248384D01*
X94760Y243860D01*
X92996D01*
X91503Y245353D01*
X84892D01*
X83511Y246734D01*
Y250358D01*
X80100Y253769D01*
X77384D01*
G01X65859Y249237D02*
Y250359D01*
X68800Y253300D01*
G01X65100Y280075D02*
Y282475D01*
G01X72835Y318544D02*
Y315736D01*
X71561Y314462D01*
Y311938D01*
X72835Y310664D01*
Y304365D01*
X74700Y302500D01*
Y298600D01*
X68400Y292300D01*
X67300D01*
X66000Y291000D01*
Y283375D01*
X65100Y282475D01*
G01X64900Y331075D02*
Y332705D01*
X67500Y335305D01*
Y339400D01*
X71906Y343806D01*
Y346425D01*
X73462Y347981D01*
G01X76500Y331205D02*
X76416D01*
X73900Y333721D01*
Y338416D01*
X74900Y339416D01*
Y340955D01*
X78142Y344197D01*
Y344542D01*
X78206Y344606D01*
Y346425D01*
X79762Y347981D01*
G01X81000Y321900D02*
Y331360D01*
X76700Y335660D01*
Y337800D01*
X78724Y339824D01*
Y339976D01*
G01X71700Y340600D02*
Y341900D01*
X73462Y343662D01*
Y344831D01*
G01X68800Y331375D02*
Y334699D01*
X73700Y339599D01*
Y341919D01*
X76612Y344831D01*
G01X71906Y349574D02*
X73462Y351130D01*
G01X68757Y349574D02*
X70313Y351130D01*
G01X75056Y346425D02*
X76612Y347981D01*
G01X68757Y346425D02*
X70313Y347981D01*
G01X75056Y352724D02*
X76612Y354280D01*
G01X75056Y349574D02*
X76612Y351130D01*
G01X67163Y354280D02*
X65607Y352724D01*
G01Y359023D02*
X67163Y360579D01*
G01Y357429D02*
X65607Y355873D01*
G01X68757Y359023D02*
X70313Y360579D01*
G01X71906Y359023D02*
X73462Y360579D01*
G01X75056Y355873D02*
X76612Y357429D01*
G01X65607Y371584D02*
X67163Y370028D01*
G01X75056Y362173D02*
X76612Y363729D01*
G01X71906Y371584D02*
X73462Y370028D01*
G01X75056Y365322D02*
X76612Y366878D01*
G01X71906Y365322D02*
X73462Y366878D01*
G01X68757Y365322D02*
X70313Y366878D01*
G01X68757Y371584D02*
X70313Y370028D01*
G01X75056Y374733D02*
X76612Y373177D01*
G01X71906Y374733D02*
X73462Y373177D01*
G01X68757Y374733D02*
X70313Y373177D01*
G01X65607Y374733D02*
X67163Y373177D01*
G01X68757Y362173D02*
X70313Y363729D01*
G01X71906Y362173D02*
X73462Y363729D01*
G01X68757Y377883D02*
X70313Y376327D01*
G01X67163D02*
X65607Y377883D01*
Y381033D01*
G01X71906Y377883D02*
X73462Y376327D01*
G01X65607Y384182D02*
X67163Y382626D01*
G01X68719Y381033D02*
X67163Y379477D01*
G01X75000Y402925D02*
Y390463D01*
X73462Y388925D01*
G01X71000Y402925D02*
Y399501D01*
X68700Y397201D01*
Y390462D01*
X67163Y388925D01*
G01X67000Y402925D02*
X64014Y399939D01*
Y392075D01*
G01X74419Y417300D02*
Y414163D01*
X74782Y413800D01*
G01X67000Y406075D02*
Y408800D01*
G01X71000Y406075D02*
Y407500D01*
X69700Y408800D01*
G01X75374Y465590D02*
Y461874D01*
X74072Y460572D01*
Y452030D01*
X69187Y440237D01*
Y429000D01*
G01X73012Y465590D02*
Y452554D01*
X68127Y440760D01*
Y431237D01*
X63945Y427055D01*
G01X92405Y131906D02*
X96381D01*
X96400Y131925D01*
G01X83950Y134950D02*
Y131449D01*
X82668Y130167D01*
X81772D01*
G01X92405Y131906D02*
X90834D01*
X88205Y132995D01*
X86250Y134950D01*
X83950D01*
G01X92200Y141540D02*
X89170D01*
G01X92200D02*
X93540D01*
X102781Y145367D01*
X125058D01*
X129500Y140925D01*
G01X155825Y158300D02*
X140300D01*
X138000Y156000D01*
X127500D01*
X126600Y155100D01*
X114373D01*
X106200Y146927D01*
X102469D01*
X96115Y144300D01*
X89341D01*
X87340Y142299D01*
Y140261D01*
X88801Y138800D01*
X89200D01*
G01X81500Y176515D02*
X90245D01*
X98830Y167930D01*
X110430D01*
X123716Y181216D01*
X132809D01*
X132900Y181125D01*
G01X81500Y170475D02*
X89824D01*
X95950Y164349D01*
Y152900D01*
G01X85794Y227069D02*
X81500Y222775D01*
G01X95347Y239985D02*
Y239167D01*
X94400Y238220D01*
Y231824D01*
X85340Y222764D01*
Y214240D01*
X83430Y212330D01*
X81000D01*
G01X90059Y241363D02*
Y231334D01*
X85794Y227069D01*
G01X84941Y241363D02*
Y232100D01*
G01X80270Y247830D02*
Y249798D01*
X79353Y250715D01*
G01X80270Y247830D02*
X83807Y244293D01*
X91063D01*
X92556Y242800D01*
X95800D01*
X101253Y248253D01*
Y250615D01*
G01X90059Y249237D02*
Y247560D01*
X90819Y246800D01*
X95000D01*
X95300Y247100D01*
G01X83500Y272575D02*
Y272526D01*
X81785Y270811D01*
Y270184D01*
X81026Y269425D01*
X79500D01*
G01X83500D02*
Y266900D01*
G01X87500Y269425D02*
X83500D01*
G01X91500D02*
Y267000D01*
G01X87500Y272575D02*
Y275900D01*
X83719Y279681D01*
X82171Y283418D01*
Y292971D01*
X83200Y294000D01*
X88400D01*
X92370Y297970D01*
Y311730D01*
X88583Y315517D01*
Y318544D01*
G01X86614D02*
Y315279D01*
X90810Y311083D01*
Y298617D01*
X87753Y295560D01*
X82553D01*
X80611Y293618D01*
Y283022D01*
X82544Y278355D01*
X83500Y277399D01*
Y272575D01*
G01X83661Y288821D02*
Y284001D01*
X85049Y280651D01*
X89900Y275800D01*
Y274175D01*
X91500Y272575D01*
G01X95500D02*
X91500D01*
G01X155225Y297000D02*
X153594Y298631D01*
Y302005D01*
X151309Y304290D01*
X130316D01*
X129593Y303567D01*
Y299423D01*
X128870Y298700D01*
X127846D01*
X127123Y299423D01*
Y303567D01*
X126400Y304290D01*
X119042D01*
X118319Y303567D01*
Y298623D01*
X117596Y297900D01*
X116572D01*
X115849Y298623D01*
Y303567D01*
X115126Y304290D01*
X114102D01*
X113379Y303567D01*
Y298623D01*
X112656Y297900D01*
X111632D01*
X110909Y298623D01*
Y303567D01*
X110186Y304290D01*
X109162D01*
X108439Y303567D01*
Y298623D01*
X107716Y297900D01*
X106692D01*
X105969Y298623D01*
Y303567D01*
X105246Y304290D01*
X104222D01*
X103499Y303567D01*
Y298623D01*
X102776Y297900D01*
X101752D01*
X101029Y298623D01*
Y303567D01*
X100306Y304290D01*
X97910D01*
X96400Y305800D01*
Y312206D01*
X95348Y313258D01*
X93758D01*
X92520Y314496D01*
Y318544D01*
G01X85500Y326700D02*
X87500Y328700D01*
Y339100D01*
X89210Y340810D01*
Y344831D01*
G01X90804Y330245D02*
X92205D01*
X92249Y330289D01*
X93288D01*
G01X95060Y327625D02*
X95200Y327765D01*
Y333300D01*
X92360Y336140D01*
Y344831D01*
G01X86061Y347981D02*
X84500Y346420D01*
Y341700D01*
X83500Y340700D01*
X80700D01*
X79976Y339976D01*
X78724D01*
G01D02*
X78700Y340000D01*
G01X78900Y336600D02*
X81500Y339200D01*
X84000D01*
X86061Y341261D01*
Y344831D01*
G01X81900Y337100D02*
X83300D01*
X87628Y341428D01*
Y346399D01*
X89210Y347981D01*
G01X81700Y342600D02*
X82911Y343811D01*
Y344831D01*
G01X90804Y333395D02*
Y346425D01*
X92360Y347981D01*
G01X87617Y352724D02*
X86061Y354280D01*
G01X90766Y349574D02*
X89210Y351130D01*
G01X93916Y349574D02*
X92360Y351130D01*
G01X93916Y352724D02*
X92360Y354280D01*
G01X81355Y355873D02*
X82911Y357429D01*
G01X90766Y352724D02*
X89210Y354280D01*
G01X86061Y351130D02*
X87617Y349574D01*
G01X78206Y359023D02*
X79762Y360579D01*
G01X90766Y355873D02*
X89210Y357429D01*
G01X87617Y355873D02*
X86061Y357429D01*
G01X90766Y359023D02*
X89210Y360579D01*
G01X78206Y355873D02*
X79762Y357429D01*
G01X81355Y349574D02*
X82911Y351130D01*
G01X81355Y346425D02*
X82911Y347981D01*
G01X78206Y349574D02*
X79762Y351130D01*
G01X93916Y355873D02*
X92360Y357429D01*
G01X87617Y359023D02*
X86061Y360579D01*
G01X81355Y377883D02*
X82911Y376327D01*
G01X78206Y381033D02*
X79762Y379477D01*
G01X81355Y387332D02*
X82911Y385776D01*
G01X79000Y395500D02*
X78232Y394732D01*
Y391441D01*
X79128Y390545D01*
X83455D01*
X84531Y389469D01*
Y381007D01*
X86061Y379477D01*
G01X81355Y384182D02*
X82911Y382626D01*
G01X84500Y402925D02*
X88500Y398925D01*
Y396260D01*
X88960Y395800D01*
X93200D01*
X93900Y395100D01*
Y389400D01*
X93425Y388925D01*
X92360D01*
G01X93916Y384182D02*
X92360Y382626D01*
G01X87617Y384182D02*
X86061Y382626D01*
G01X90766Y377883D02*
X89210Y376327D01*
G01X87617Y390481D02*
X86061Y388925D01*
G01X81355Y381033D02*
X82911Y379477D01*
G01X78206Y377883D02*
X79762Y376327D01*
G01X87617Y387332D02*
X86061Y385776D01*
G01X93916Y381033D02*
X92360Y379477D01*
G01X90766Y381033D02*
X89210Y379477D01*
G01X93916Y387332D02*
X92360Y385776D01*
G01X87617Y377883D02*
X86061Y376327D01*
G01X90766Y390481D02*
X89210Y388925D01*
G01X90766Y387332D02*
X89210Y385776D01*
G01X90766Y384182D02*
X89210Y382626D01*
G01X86061Y392075D02*
Y394539D01*
X84600Y396000D01*
Y398400D01*
X81500Y401500D01*
Y406264D01*
X79690Y408074D01*
Y409438D01*
X79551Y409577D01*
Y416240D01*
X80011Y416700D01*
X85800D01*
X87100Y418000D01*
Y424100D01*
X84320Y426880D01*
Y430510D01*
G01X92500Y402925D02*
X97064Y398361D01*
Y390479D01*
X95510Y388925D01*
G01X79000Y402925D02*
Y398299D01*
X81200Y396099D01*
Y393786D01*
X82911Y392075D01*
G01X88500Y402925D02*
X95510Y395915D01*
Y392075D01*
G01X92360Y394175D02*
Y392075D01*
G01X89210Y394175D02*
Y392075D01*
G01X84500Y406075D02*
Y409460D01*
X84801Y409760D01*
G01X89675Y412500D02*
Y417000D01*
G01X83081Y413560D02*
X84141Y412500D01*
X89675D01*
G01Y417000D02*
Y421940D01*
G01X92500Y406075D02*
Y408630D01*
G01X88500Y406075D02*
X86704Y407871D01*
X86481D01*
G01X89675Y421940D02*
Y424475D01*
X91415Y426215D01*
Y428020D01*
G01X88565Y426535D02*
Y433040D01*
G01D02*
X96540D01*
X103900Y440400D01*
Y447640D01*
G01X79600Y426400D02*
Y430300D01*
X87200Y437900D01*
X89700D01*
G01X100472Y24764D02*
X108501Y32793D01*
Y38924D01*
X108500Y38925D01*
G01Y42075D02*
X107000Y43575D01*
Y44500D01*
G01X102800Y84925D02*
Y84524D01*
X101845Y83569D01*
Y74655D01*
X103000Y73500D01*
X104500D01*
G01X113760Y74441D02*
X112449Y73130D01*
X104870D01*
X104500Y73500D01*
G01X113760Y79559D02*
X111000D01*
X110559Y80000D01*
X107575D01*
G01X106800Y84925D02*
X102800D01*
G01X105030Y96300D02*
X105422Y95352D01*
X102800Y89020D01*
Y88075D01*
G01X105030Y96300D02*
Y103870D01*
X106760Y105600D01*
X109175D01*
X111075Y107500D01*
G01X102999Y131799D02*
Y133001D01*
X100925Y135075D01*
X100400D01*
G01X137525Y140752D02*
Y134025D01*
X136580Y133080D01*
X128320D01*
X120900Y140500D01*
X105873D01*
X101481Y138681D01*
X100400Y137600D01*
Y135075D01*
G01Y131925D02*
X96400D01*
G01X98720Y236980D02*
X99284Y237544D01*
Y239985D01*
G01X106800Y259675D02*
X105177D01*
X104330Y258828D01*
Y256530D01*
X102613Y254813D01*
Y246813D01*
X97316Y241516D01*
Y239985D01*
G01Y250615D02*
Y257709D01*
X97300Y257725D01*
G01X110241Y249540D02*
X108430Y251351D01*
Y254895D01*
X106800Y256525D01*
G01X95300Y247100D02*
X93500Y248900D01*
Y255075D01*
X93075Y255500D01*
G01X101500Y257925D02*
X97500D01*
X97300Y257725D01*
G01X110800Y260275D02*
X110200Y259675D01*
X106800D01*
G01X101500Y261075D02*
X103275D01*
X104276Y262076D01*
X106800D01*
G01X93504Y288821D02*
Y283496D01*
X94200Y282800D01*
Y277875D01*
X99500Y272575D01*
G01X107400Y273475D02*
X106275Y274600D01*
X103100D01*
X101800Y275900D01*
Y281676D01*
X104984Y284860D01*
X106783D01*
X107283Y285360D01*
Y288821D01*
G01X103500Y272575D02*
X99175Y276900D01*
X97100D01*
X95472Y278528D01*
Y288821D01*
G01X155225Y305100D02*
X153915Y306410D01*
X103901D01*
X103671Y306640D01*
X103660D01*
X102080Y308220D01*
Y312920D01*
X101130Y313870D01*
X99531D01*
X98425Y314976D01*
Y318544D01*
G01X104331D02*
Y314469D01*
X105000Y313800D01*
X105919D01*
X106829Y312890D01*
X109580D01*
X113770Y308700D01*
X119157D01*
X119880Y309423D01*
Y310277D01*
X120603Y311000D01*
X121627D01*
X122350Y310277D01*
Y309423D01*
X123073Y308700D01*
X129876D01*
X130599Y309423D01*
Y310277D01*
X131322Y311000D01*
X132346D01*
X133069Y310277D01*
Y309423D01*
X133792Y308700D01*
X134816D01*
X135539Y309423D01*
Y310277D01*
X136262Y311000D01*
X137286D01*
X138009Y310277D01*
Y309423D01*
X138732Y308700D01*
X148500D01*
X153360Y313560D01*
X155224D01*
G01X102362Y318544D02*
Y314938D01*
X103140Y314160D01*
Y308660D01*
X104200Y307600D01*
X104211D01*
X104341Y307470D01*
X153078D01*
X155225Y309617D01*
Y309700D01*
G01Y301000D02*
Y302182D01*
X152057Y305350D01*
X99950D01*
X97700Y307600D01*
Y313100D01*
X96300Y314500D01*
X95300D01*
X94488Y315312D01*
Y318544D01*
G01X100500Y328547D02*
Y330815D01*
X100960Y331275D01*
X103100D01*
G01X121875Y342500D02*
Y341375D01*
X120700Y340200D01*
X114400D01*
X109318Y335118D01*
Y327172D01*
X108035Y325889D01*
X104388D01*
X103000Y324501D01*
Y323800D01*
G01X113918Y331563D02*
X112562D01*
X111618Y330619D01*
Y326218D01*
X108679Y323279D01*
X106865D01*
X106852Y323292D01*
G01X98000Y328125D02*
Y325900D01*
X97800Y325700D01*
G01X103100Y331275D02*
Y332400D01*
X100928Y334572D01*
Y339536D01*
X97103Y343361D01*
Y346425D01*
X98659Y347981D01*
G01X99026Y338368D02*
X97526D01*
X95510Y340384D01*
Y344831D01*
G01X118725Y342500D02*
X100990D01*
X98659Y344831D01*
G01X101809D02*
X100253Y346387D01*
G01X98000Y331275D02*
Y332404D01*
X93954Y336450D01*
Y346425D01*
X95510Y347981D01*
G01X101809D02*
X103365Y346425D01*
G01X97066Y349574D02*
X95510Y351130D01*
G01X100215Y349574D02*
X98659Y351130D01*
G01X108500Y402925D02*
Y401736D01*
X103364Y396600D01*
Y390480D01*
X101809Y388925D01*
G01X100500Y402925D02*
X100264Y402689D01*
Y390530D01*
X98659Y388925D01*
G01X97066Y387332D02*
X95510Y385776D01*
G01X112500Y402925D02*
X108275Y398700D01*
X107458D01*
X104958Y396200D01*
Y392075D01*
G01X104500Y402925D02*
X101809Y400234D01*
Y392075D01*
G01X100500Y406075D02*
X100457Y406118D01*
Y409100D01*
G01X113169Y466378D02*
Y455032D01*
X115100Y453101D01*
Y444201D01*
X105600Y434701D01*
Y430100D01*
X107200Y428500D01*
Y419801D01*
X108701Y418300D01*
G01X98976Y415200D02*
X98680Y415496D01*
Y425375D01*
G01X104500Y406075D02*
Y407711D01*
X108336Y411547D01*
G01X115532Y465590D02*
Y455368D01*
X117000Y453900D01*
Y442800D01*
X111200Y437000D01*
Y436989D01*
X107700Y433489D01*
Y430199D01*
X111000Y426899D01*
Y423500D01*
X109800Y422300D01*
G01X104112Y422946D02*
X105740Y424574D01*
Y427641D01*
X103070Y430311D01*
Y432630D01*
G01D02*
Y434671D01*
X112300Y443901D01*
Y453299D01*
X110807Y454792D01*
Y465590D01*
G01X103461Y425875D02*
Y427610D01*
X100000Y431071D01*
Y434299D01*
X110000Y444299D01*
Y453001D01*
X108445Y454556D01*
Y465590D01*
G01X94565Y428020D02*
X95705Y426880D01*
X97175D01*
X98680Y425375D01*
G01X117047Y24764D02*
X120500Y28217D01*
Y38925D01*
G01X108500D02*
X112500D01*
G01D02*
X116500D01*
G01X118224Y47760D02*
X122340D01*
X123100Y47000D01*
Y42800D01*
X124000Y41900D01*
X125260D01*
G01X112600Y52800D02*
X111860Y53540D01*
Y54886D01*
X111506Y55240D01*
X108776D01*
G01Y51500D02*
X111000D01*
X112400Y50100D01*
X124000D01*
G01X111000Y77000D02*
X113760D01*
G01D02*
X114260Y77500D01*
X120740D01*
X121240Y77000D01*
G01Y74441D02*
X121999Y75200D01*
X123606D01*
X126200Y77794D01*
Y79425D01*
G01X129300Y82650D02*
X127070Y84880D01*
X123678D01*
X119098Y80300D01*
X114570D01*
X113829Y79559D01*
X113760D01*
G01X121240D02*
X123508D01*
X123740Y79791D01*
G01X111075Y102000D02*
X112875Y100200D01*
X116375D01*
X118175Y102000D01*
G01X111075D02*
Y104600D01*
G01X123474Y101063D02*
X119112D01*
X118175Y102000D01*
G01X111075Y107500D02*
X112975Y109400D01*
X116375D01*
X118175Y107600D01*
G01X123474Y103032D02*
X120067D01*
X118175Y104924D01*
Y107600D01*
G01X112300Y112300D02*
X109970D01*
X109350Y112920D01*
Y115501D01*
G01X123474Y118563D02*
X122760D01*
X122300Y118103D01*
Y116700D01*
X123425Y115575D01*
Y114000D01*
G01X118100Y112300D02*
X121200D01*
X122500Y111000D01*
X123325D01*
G01X112300Y118500D02*
X109200D01*
G01X118100D02*
X117575Y119025D01*
Y123500D01*
G01X118100Y118500D02*
Y116500D01*
X119075Y115525D01*
X120500D01*
G01X118100Y118500D02*
X118400D01*
X120432Y120532D01*
X123474D01*
G01Y108937D02*
X120724D01*
G01X112300Y128500D02*
X109200D01*
G01X123425Y131000D02*
X119570D01*
X118990Y131580D01*
G01D02*
Y129390D01*
X118100Y128500D01*
G01D02*
X118400D01*
X122432Y124468D01*
X123474D01*
G01X141500Y241575D02*
X140575Y242500D01*
X131490D01*
X130560Y241570D01*
Y238590D01*
X126860Y234890D01*
X121200D01*
G01X120331Y239925D02*
X117494D01*
X115359Y242060D01*
G01D02*
Y241459D01*
X113100Y239200D01*
X112900D01*
G01X108000Y237200D02*
Y247299D01*
X110241Y249540D01*
G01X122500Y256775D02*
X122365D01*
X120020Y254430D01*
G01X110241Y242060D02*
Y245741D01*
X111600Y247100D01*
X116640D01*
X117100Y247560D01*
Y252447D01*
X118693Y256293D01*
X121500Y259100D01*
X127000D01*
X127600Y259700D01*
G01X119600Y261500D02*
X118510Y260410D01*
X115359Y252805D01*
Y249540D01*
G01X122500Y253625D02*
X126500D01*
G01X119760Y271276D02*
X120576D01*
X122350Y273050D01*
Y276686D01*
X119760Y279276D01*
G01X115260D02*
X117500Y277036D01*
Y272600D01*
X116176Y271276D01*
X115260D01*
G01X124500Y261125D02*
X124125Y261500D01*
X119600D01*
G01X109252Y288821D02*
X109200Y288769D01*
Y273011D01*
X111136Y271075D01*
X111500D01*
G01X119760Y276126D02*
X120070Y275816D01*
Y273700D01*
G01X115260Y276126D02*
X115000Y275866D01*
Y273700D01*
G01X119760Y279276D02*
X121063Y280579D01*
Y288821D01*
G01X119095D02*
Y283111D01*
X115260Y279276D01*
G01X111100Y279275D02*
X112065D01*
X113690Y280900D01*
Y284530D01*
X113189Y285031D01*
Y288821D01*
G01X113918Y328413D02*
Y325282D01*
X115646Y323554D01*
X119846D01*
X122047Y321353D01*
Y318544D01*
G01X117918Y328413D02*
X121918D01*
G01D02*
Y324735D01*
X124229Y322424D01*
X124869D01*
X125093Y322200D01*
X125100D01*
X125984Y321316D01*
Y318544D01*
G01X191420Y354710D02*
X188310D01*
X176800Y343200D01*
Y340310D01*
X155610Y319120D01*
X154087D01*
X153150Y320057D01*
Y322543D01*
X157460Y326853D01*
Y333347D01*
X150717Y340090D01*
X138390D01*
X137300Y339000D01*
X130200D01*
X126700Y342500D01*
X121875D01*
G01X117918Y331563D02*
X122579Y336224D01*
X125900Y337600D01*
G01X115535Y335235D02*
X118536D01*
X123501Y340200D01*
X126200D01*
X129100Y337300D01*
X137900D01*
X139130Y338530D01*
X150070D01*
X155900Y332700D01*
Y327500D01*
X154600Y326200D01*
X150600D01*
X149200Y324800D01*
Y321800D01*
X153440Y317560D01*
X156257D01*
X178360Y339663D01*
Y342553D01*
X183599Y347792D01*
X184100Y348000D01*
X188000D01*
X189740Y346260D01*
X197418D01*
X197775Y346617D01*
G01X114700Y351200D02*
X116900Y349000D01*
Y347301D01*
X117801Y346400D01*
X118725D01*
G01X118800Y354125D02*
X118817Y354108D01*
Y350392D01*
X118725Y350300D01*
G01X111330Y357800D02*
X115580D01*
X116862Y356518D01*
Y352163D01*
X118725Y350300D01*
G01X118800Y357275D02*
Y356961D01*
X119261Y356500D01*
X121400D01*
X124350Y353550D01*
Y352450D01*
G01X124300Y348800D02*
X123400Y349700D01*
X122475D01*
X121875Y350300D01*
G01X117410Y381350D02*
Y370690D01*
X120200Y367900D01*
X123100D01*
X127240Y363760D01*
Y360439D01*
X128700Y358979D01*
Y345300D01*
X130200Y343800D01*
X143900D01*
X145000Y344900D01*
X153901D01*
X155300Y343501D01*
Y340300D01*
X159300Y336300D01*
Y325400D01*
X155000Y321100D01*
G01X119100Y396225D02*
X116900Y394025D01*
Y386500D01*
X120500Y382900D01*
Y375200D01*
X122047Y373653D01*
Y372260D01*
G01X112500Y406075D02*
X113525D01*
X114300Y405300D01*
Y387200D01*
X119300Y382200D01*
Y371699D01*
X120899Y370100D01*
X123300D01*
X125500Y372300D01*
Y380383D01*
X124200Y381683D01*
Y384100D01*
X125000Y384900D01*
X149759D01*
X149937Y384722D01*
X154977D01*
X156193Y383506D01*
X163006D01*
X165500Y386000D01*
G01X116500Y403025D02*
X117874D01*
X119100Y401799D01*
Y399375D01*
G01D02*
X122525D01*
X125174Y396726D01*
Y393916D01*
G01X132700Y402700D02*
X132200Y403200D01*
X122800D01*
X121500Y404500D01*
Y407000D01*
X120000Y408500D01*
X116786D01*
X112796Y412490D01*
G01X113000Y416200D02*
X110951Y418248D01*
X110032Y420467D01*
X109800Y420699D01*
Y422300D01*
G01X155452Y401000D02*
X151852Y397400D01*
X146800D01*
X145900Y398300D01*
X142966D01*
X140793Y397400D01*
X134300D01*
X133050Y398650D01*
Y400350D01*
X134800Y402100D01*
Y404300D01*
X133700Y405400D01*
X129700D01*
X125400Y409700D01*
X118432D01*
X116632Y411500D01*
G01X108500Y406075D02*
Y408680D01*
G01X108424Y415200D02*
Y415126D01*
X111060Y412490D01*
X112796D01*
G01D02*
X113415D01*
X115925Y415000D01*
G01X112800Y421600D02*
Y430250D01*
X115880Y433330D01*
Y435581D01*
X122100Y441801D01*
Y452600D01*
X120256Y454444D01*
Y466378D01*
G01X117894Y465590D02*
Y455005D01*
X120700Y452199D01*
Y442701D01*
X114250Y436251D01*
Y433900D01*
X111950Y431600D01*
X110200D01*
G01X127047Y24764D02*
X129500Y27217D01*
Y42700D01*
X131259Y44459D01*
X132740D01*
G01X125800Y47330D02*
X129330D01*
X130575Y48575D01*
Y50000D01*
G01X124000Y50100D02*
X127325D01*
X127425Y50000D01*
G01X126200Y79425D02*
X129325D01*
X131160Y81260D01*
X131470D01*
G01X136319Y81181D02*
X134519D01*
X127400Y88300D01*
Y100603D01*
X126940Y101063D01*
X126526D01*
G01X136319Y85118D02*
X134382D01*
X131600Y87900D01*
Y92400D01*
X129500Y94500D01*
Y100900D01*
X127368Y103032D01*
X126526D01*
G01Y101063D02*
X123474D01*
G01X126526Y103032D02*
X123474D01*
G01X136319Y92992D02*
X140708D01*
X142400Y91300D01*
G01X126526Y106968D02*
X128032D01*
X128546Y106454D01*
X129240Y104779D01*
Y104074D01*
X131560Y101754D01*
Y95740D01*
X134308Y92992D01*
X136319D01*
G01X123474Y106968D02*
X126526D01*
G01X136319Y100866D02*
X135930D01*
X133377Y101924D01*
X131460Y103841D01*
X130800Y105434D01*
X129834Y107766D01*
X129112Y108488D01*
X128028Y108937D01*
X126526D01*
G01X123474Y118563D02*
X126526D01*
G01X123325Y111000D02*
Y113900D01*
X123425Y114000D01*
G01X136319Y108740D02*
X134260D01*
X128374Y114626D01*
Y117226D01*
X127037Y118563D01*
X126526D01*
G01Y120532D02*
X123474D01*
G01X126526D02*
X127435D01*
X128197Y119770D01*
X130630D01*
X131800Y118600D01*
Y117500D01*
X132686Y116614D01*
X136319D01*
G01X126526Y108937D02*
X123474D01*
G01X126526Y124468D02*
X123474D01*
G01X126526D02*
X126546Y124488D01*
X127455D01*
X128197Y125230D01*
X130459D01*
X131201Y124488D01*
X136319D01*
G01X129500Y144075D02*
X133500D01*
G01X129500D02*
X128607D01*
X124801Y147881D01*
Y148130D01*
G01D02*
X126151Y149480D01*
X128950D01*
X129760Y150290D01*
Y152985D01*
G01X137240D02*
Y151941D01*
X136040Y150741D01*
Y145387D01*
X137525Y143902D01*
G01X137540Y169500D02*
Y163915D01*
X137240Y163615D01*
G01X122900Y170100D02*
X123100D01*
X124100Y171100D01*
Y177100D01*
X126100Y179100D01*
X135100D01*
X135600Y179600D01*
Y185000D01*
X134100Y186500D01*
X129300D01*
X127200Y188600D01*
Y193000D01*
X129000Y194800D01*
X132100D01*
X134370Y192530D01*
X140830D01*
G01X140425Y175200D02*
X138001D01*
X135901Y173100D01*
X133325D01*
X133000Y173425D01*
G01X140425Y175200D02*
X139319Y174094D01*
X139094D01*
X137540Y172540D01*
Y169500D01*
G01X123906Y188194D02*
X122800Y189300D01*
Y199654D01*
X124779Y201633D01*
G01X132900Y184275D02*
X132808Y184183D01*
X131186D01*
X130578Y183575D01*
X128525D01*
X123906Y188194D01*
G01X142150Y184000D02*
X139400D01*
X132090Y191310D01*
X129810D01*
G01X143742Y203395D02*
X143137Y204000D01*
X138235D01*
X137075Y202840D01*
Y201500D01*
G01X126153Y199079D02*
X128574Y201500D01*
X133925D01*
G01X128720Y227765D02*
X127995D01*
X126400Y226170D01*
Y225610D01*
X125984Y225194D01*
X124226D01*
G01X135824Y240260D02*
X135260D01*
X132398Y237398D01*
Y232400D01*
G01D02*
Y227767D01*
G01X126376Y247740D02*
X123340D01*
X122876Y247276D01*
Y245300D01*
G01X138000Y244600D02*
X138900Y245500D01*
Y254100D01*
X134400Y258600D01*
X132925D01*
X129625Y261900D01*
G01X126500Y253625D02*
X129600Y250525D01*
Y244460D01*
X129140Y244000D01*
X126376D01*
G01X137083Y278045D02*
Y278001D01*
X139200Y275884D01*
Y273490D01*
X137014Y268213D01*
X132541Y263740D01*
X127260D01*
X126800Y264200D01*
X125819Y266567D01*
X124260Y268126D01*
G01X133000Y271075D02*
X134260Y272335D01*
Y274940D01*
X133267Y275933D01*
Y280833D01*
X132874Y281226D01*
Y288821D01*
G01X128760Y279276D02*
X130590Y277446D01*
Y272942D01*
X128924Y271276D01*
X128760D01*
G01X124260D02*
X125476D01*
X126930Y272730D01*
Y276606D01*
X124260Y279276D01*
G01X124500Y264275D02*
Y264176D01*
X126776Y261900D01*
X129625D01*
G01X128760Y276126D02*
Y273701D01*
G01Y279276D02*
X125000Y283036D01*
Y288821D01*
G01X123032D02*
Y280504D01*
X124260Y279276D01*
G01X132874Y288821D02*
Y299974D01*
X135900Y303000D01*
X149435D01*
X150306Y302129D01*
X150305D01*
X150293Y302117D01*
G01X145918Y328413D02*
Y326718D01*
X143300Y324100D01*
X134800D01*
X133858Y323158D01*
Y318544D01*
G01X137918Y328413D02*
X133918D01*
G01D02*
Y325617D01*
X131890Y323589D01*
Y318544D01*
G01X129918Y328413D02*
X125918D01*
G01X127953Y318544D02*
Y325846D01*
X125918Y327881D01*
Y328413D01*
G01X133918Y331563D02*
X134263D01*
X136100Y333400D01*
Y334000D01*
G01X129918Y331563D02*
X132455Y334100D01*
X133300D01*
G01X136000Y341000D02*
X130500D01*
X127140Y344360D01*
Y349660D01*
X124350Y352450D01*
G01X153419Y341978D02*
X152378D01*
X152050Y341650D01*
X136650D01*
X136000Y341000D01*
G01X136825Y348300D02*
Y351900D01*
G01Y348300D02*
X135125Y346600D01*
X132100D01*
G01D02*
X131800D01*
X130200Y348200D01*
Y352769D01*
X130921Y353490D01*
X132440D01*
X132900Y353950D01*
Y355490D01*
X132440Y355950D01*
X130921D01*
X130200Y356671D01*
Y369064D01*
X130660Y369524D01*
X137553D01*
X138013Y369064D01*
Y365197D01*
G01X131540Y394690D02*
X133110D01*
X140100Y387700D01*
X147399D01*
X154199Y394500D01*
X191799D01*
X193059Y393240D01*
X198660D01*
X201000Y390900D01*
X211675D01*
X213500Y389075D01*
G01X145703Y370700D02*
Y376697D01*
X139700Y382700D01*
X126340D01*
G01X138013Y405749D02*
Y409488D01*
X136901Y410600D01*
Y417801D01*
X137900Y418800D01*
X142375D01*
X143000Y419425D01*
G01X133025Y429000D02*
Y426711D01*
X132455Y426141D01*
X131240Y423207D01*
Y418360D01*
X132470Y417130D01*
Y415655D01*
X133500Y414625D01*
Y409110D01*
G01X133025Y429000D02*
X135211Y431186D01*
X136286D01*
X137200Y432100D01*
Y438190D01*
X145048Y446038D01*
Y460354D01*
X144311Y461091D01*
Y465590D01*
G01X133070Y420874D02*
X139624D01*
X140900Y422150D01*
Y425900D01*
X141914Y426914D01*
Y429386D01*
X141440Y429860D01*
Y431614D01*
X140979Y432075D01*
X139900D01*
G01X125930Y433110D02*
X140660Y447840D01*
Y457950D01*
X139587Y459023D01*
Y466378D01*
G01X148400Y164525D02*
X150642Y162283D01*
X153218D01*
X154235Y163300D01*
X155425D01*
X155525Y163400D01*
G01X148370Y172175D02*
X145765Y169570D01*
X144500D01*
G01X156125Y167100D02*
X154455Y168770D01*
X150144D01*
X148370Y170544D01*
Y172175D01*
G01X137900Y179160D02*
X140435D01*
G01X143585D02*
X145244Y177501D01*
X146882D01*
G01X150619Y178646D02*
Y180690D01*
X148715Y182594D01*
X148519D01*
G01X155625Y174800D02*
X152626D01*
X150956Y176470D01*
X149580Y177040D01*
X148800Y177820D01*
Y177876D01*
X148789Y177887D01*
Y179862D01*
X147897Y180754D01*
X143637Y182513D01*
X142150Y184000D01*
G01X155725Y191700D02*
X154094D01*
X153794Y191400D01*
X150601D01*
X148314Y193687D01*
G01D02*
X144885Y197116D01*
X143208D01*
X140903Y199421D01*
G01X151669Y182594D02*
Y182678D01*
X153999Y185008D01*
X157428D01*
X158684Y183752D01*
Y182644D01*
G01X150651Y187354D02*
X153051D01*
G01X155500Y200500D02*
X153500D01*
X152500Y199500D01*
G01X150467Y222191D02*
X152433D01*
X154830Y219794D01*
X156028D01*
G01X153500Y232075D02*
X152500Y233075D01*
Y234200D01*
X153100Y234800D01*
G01X145500Y227700D02*
Y229500D01*
X146000Y230000D01*
Y233294D01*
X145600Y233694D01*
Y235325D01*
G01X141280Y256310D02*
Y248120D01*
X147564Y241836D01*
X149790D01*
X151722Y241036D01*
X153834D01*
X155259Y239611D01*
X155987Y238521D01*
X157099Y238060D01*
X159330D01*
X163030Y234360D01*
Y233370D01*
X173700Y222700D01*
X178349D01*
X179902Y221147D01*
G01X145600Y238475D02*
X146885Y239760D01*
X153248D01*
X156008Y237000D01*
X157158D01*
X158432Y236472D01*
X159370Y234205D01*
Y233065D01*
X162623Y225213D01*
X165236Y222600D01*
X167200D01*
G01X149500Y232575D02*
Y236330D01*
X151040Y237870D01*
G01X142702Y227817D02*
Y228145D01*
X144574Y230017D01*
Y233427D01*
X141500Y236501D01*
Y238425D01*
G01X152865Y242750D02*
Y246742D01*
X152000Y247607D01*
Y256300D01*
X146710Y261590D01*
Y278210D01*
X148900Y280400D01*
X151800D01*
X154400Y277800D01*
X162400D01*
X163500Y278900D01*
X178700D01*
X179072Y278528D01*
X179217D01*
G01X149215Y267745D02*
X149945D01*
X150700Y266990D01*
X153019D01*
X158000Y271971D01*
Y273711D01*
G01X150240Y277940D02*
X152380Y275800D01*
X154941D01*
X155441Y275300D01*
Y273711D01*
G01X137795Y318544D02*
Y321995D01*
X138300Y322500D01*
X144005D01*
X149918Y328413D01*
G01D02*
X153918D01*
G01X141918D02*
X145918D01*
G01X149918Y331563D02*
X149037D01*
X147600Y333000D01*
Y333900D01*
X144800Y336700D01*
G01X145918Y331563D02*
Y332882D01*
X144700Y334100D01*
G01X141045Y355309D02*
Y352970D01*
X139975Y351900D01*
G01X150900Y360325D02*
X153925D01*
X155720Y362120D01*
Y372730D01*
X157660Y374670D01*
X169370D01*
X174100Y379400D01*
X187400D01*
G01X153000Y348600D02*
X150800Y350800D01*
Y352100D01*
X146400Y356500D01*
Y360811D01*
X148013Y362424D01*
Y365197D01*
G01X142511Y393690D02*
X150890D01*
X153400Y396200D01*
X185000D01*
X188300Y399500D01*
X190100D01*
X194800Y394800D01*
X199500D01*
X201300Y393000D01*
X213968D01*
X215670Y394702D01*
Y396634D01*
X215430Y396874D01*
Y402329D01*
X218401Y405300D01*
X222600D01*
X224300Y407000D01*
Y409080D01*
X223287Y411525D01*
X222232Y412580D01*
X216620D01*
X214480Y414720D01*
Y421547D01*
X215734Y424582D01*
X216186Y425034D01*
X216664Y426189D01*
X219600Y429125D01*
G01X143013Y405749D02*
Y408802D01*
X146505Y417235D01*
Y417445D01*
X146596Y417536D01*
Y419159D01*
X146505Y419250D01*
G01X143000Y422575D02*
X144564D01*
X146069Y421070D01*
X150501D01*
X160540Y416912D01*
G01X162100Y414000D02*
X159491Y414521D01*
X159043Y414706D01*
X157496Y415741D01*
X149836Y418913D01*
X149726Y419179D01*
X149655Y419250D01*
G01X153575Y429000D02*
X154200Y428375D01*
Y423710D01*
X153590Y423100D01*
X152200D01*
G01X148041Y426700D02*
X145366Y429375D01*
X145200D01*
G01D02*
X143100Y431475D01*
Y434701D01*
X152642Y444243D01*
X153760Y446942D01*
Y465590D01*
G01X139900Y432075D02*
X139855Y432120D01*
Y437471D01*
X147000Y444616D01*
Y461001D01*
X146673Y461328D01*
Y465590D01*
G01X151398D02*
Y449930D01*
G01X156200Y111600D02*
X157700Y110100D01*
Y107900D01*
X158460Y107140D01*
X161877D01*
G01X155300Y101225D02*
Y101325D01*
X157375Y103400D01*
X161877D01*
G01X155300Y104375D02*
Y109100D01*
X152800Y111600D01*
G01X164400Y119925D02*
X163176D01*
X162608Y120493D01*
Y124891D01*
X166417Y128700D01*
X166733D01*
G01X164400Y123075D02*
Y124200D01*
X166492Y126292D01*
X166892D01*
X166900Y126300D01*
X167592D01*
X168800Y126800D01*
G01X159480Y153077D02*
X162573D01*
X163730Y151920D01*
Y148290D01*
X164670Y147350D01*
X166297D01*
X167251Y147988D01*
X169282Y152893D01*
X169468Y153826D01*
Y157675D01*
X171099Y159306D01*
X172700Y163174D01*
X175080Y165554D01*
X176118Y165984D01*
X177613D01*
X178758Y166458D01*
X179902Y167603D01*
G01X165690Y149622D02*
X166847Y152415D01*
X167300Y154693D01*
Y155397D01*
X166883Y157497D01*
X166963Y157901D01*
X169618Y162864D01*
X173475Y166721D01*
X175603Y167603D01*
X176752D01*
G01X156330Y153077D02*
X156481Y153228D01*
Y155933D01*
G01X179902Y170753D02*
X178346Y169197D01*
X176124D01*
X171981Y167481D01*
X165600Y161100D01*
X162300D01*
X159500Y158300D01*
X158975D01*
G01X176752Y177052D02*
X169146Y169446D01*
Y166791D01*
X167197Y164842D01*
X164982D01*
G01D02*
X162582D01*
X162571Y164853D01*
X161859D01*
X160406Y163400D01*
X158675D01*
G01X164472Y169902D02*
X161870Y167300D01*
X161106D01*
X160906Y167100D01*
X159275D01*
G01X158684Y182644D02*
X159675Y183635D01*
X162458D01*
X164601Y181492D01*
G01X176752Y183351D02*
X166460D01*
X164601Y181492D01*
G01X158775Y174800D02*
Y178663D01*
X158791Y178679D01*
G01X158775Y174800D02*
X160830D01*
X164130Y178100D01*
X170000D01*
X173687Y181787D01*
X178338D01*
X179902Y183351D01*
G01X174569Y180202D02*
X169349Y174982D01*
X164426D01*
G01D02*
X160444Y171000D01*
X158775D01*
G01X164472Y169902D02*
X166758D01*
X175502Y178646D01*
X178346D01*
X179902Y180202D01*
G01X165000Y191807D02*
X164407Y192400D01*
X160574D01*
X159874Y191700D01*
X158875D01*
G01X165000Y191807D02*
X166918D01*
X170041Y194930D01*
X171559D01*
X172095Y194394D01*
X181495D01*
X183051Y195950D01*
G01X164879Y186543D02*
X163479Y187943D01*
X159414D01*
X158825Y187354D01*
G01X164879Y186543D02*
X166013Y185409D01*
X174040D01*
X175132Y186501D01*
X176752D01*
G01X153051Y187354D02*
X155675D01*
G01X164800Y198000D02*
X159675D01*
X157375Y195700D01*
G01X175196Y203805D02*
X173566Y202175D01*
Y197583D01*
X172553Y196570D01*
X169031D01*
X167601Y198000D01*
X164800D01*
G01X160500Y205675D02*
X161946D01*
X164531Y208260D01*
Y211731D01*
X165100Y212300D01*
X166300D01*
G01X160500Y202525D02*
X158475Y200500D01*
X155500D01*
G01X160032Y219794D02*
X156028D01*
G01X156713Y257454D02*
X155155D01*
X154400Y256699D01*
Y248546D01*
X156426Y246520D01*
X156551D01*
X157961Y245110D01*
X159389D01*
X168600Y235899D01*
Y233203D01*
X171243Y230560D01*
X175714D01*
X175749Y230595D01*
X176752D01*
G01X156973Y249436D02*
X158939Y247470D01*
X159429D01*
X170000Y236899D01*
Y235700D01*
X172780Y232920D01*
X175000D01*
X175714Y232206D01*
X177393D01*
X179004Y230595D01*
X179902D01*
G01X156015Y242750D02*
X157251D01*
X163670Y236331D01*
Y235341D01*
X170811Y228200D01*
X173700D01*
X176752Y225148D01*
Y224296D01*
G01X160713Y257454D02*
X162091D01*
X162800Y256745D01*
Y249600D01*
X163298Y249102D01*
Y248233D01*
X163726Y247805D01*
X164595D01*
X174284Y238116D01*
X176785D01*
X179902Y234999D01*
Y233745D01*
G01X165013Y249436D02*
X172552Y241897D01*
X175903D01*
X180967Y236833D01*
Y235829D01*
X183051Y233745D01*
G01X156973Y252586D02*
Y254997D01*
X156970Y255000D01*
G01X165013Y252586D02*
Y254986D01*
G01X160973Y252586D02*
Y254986D01*
G01X164801Y257386D02*
X166101D01*
X167300Y256187D01*
Y252322D01*
X169261Y247588D01*
X173388Y243461D01*
X177339D01*
X186201Y234599D01*
Y233745D01*
G01X160973Y249436D02*
Y248528D01*
X173006Y236495D01*
X176305D01*
X178300Y234500D01*
Y233000D01*
X179169Y232131D01*
X181515D01*
X183051Y230595D01*
G01X160713Y260604D02*
Y263177D01*
X160590Y263300D01*
G01X156713Y260604D02*
X157000Y260891D01*
Y263220D01*
X156970Y263250D01*
G01X164801Y260536D02*
Y263299D01*
X164800Y263300D01*
G01X158375Y305100D02*
X159675Y303800D01*
X162247D01*
X164000Y302047D01*
Y297400D01*
X159500Y292900D01*
Y290401D01*
X161959Y287942D01*
X162981D01*
X164757Y289718D01*
X165880D01*
X166605Y288993D01*
Y288071D01*
X164728Y286194D01*
Y285173D01*
X167001Y282900D01*
X169832D01*
X170332Y283400D01*
Y294977D01*
X171055Y295700D01*
X172079D01*
X172802Y294977D01*
Y292736D01*
X173525Y292013D01*
X176677D01*
X177400Y291290D01*
Y290266D01*
X176677Y289543D01*
X173525D01*
X172802Y288820D01*
Y283000D01*
X173302Y282500D01*
X176799D01*
X180099Y285800D01*
X181201D01*
X182801Y284200D01*
X184535D01*
X185035Y284700D01*
Y285581D01*
X180419Y290197D01*
Y291100D01*
X180919Y291600D01*
X182509D01*
X186781Y287328D01*
X187904D01*
X189876Y289300D01*
X190898D01*
X191623Y288575D01*
Y287553D01*
X191462Y287392D01*
Y286370D01*
X193905Y283928D01*
Y282906D01*
X193180Y282181D01*
X192158D01*
X189715Y284623D01*
X188693D01*
X185465Y281394D01*
Y280372D01*
X187837Y278000D01*
X192500D01*
G01X158375Y297000D02*
Y295176D01*
X157700Y294501D01*
Y289200D01*
X166100Y280800D01*
X177500D01*
X178000Y281300D01*
X179599D01*
X184229Y276670D01*
X185430D01*
X187200Y274900D01*
X188500D01*
G01X160559Y281289D02*
Y283140D01*
X158750Y284949D01*
G01X158375Y301000D02*
X160506D01*
X160850Y301344D01*
G01X162100Y291600D02*
X166000Y295500D01*
Y305500D01*
G01X155224Y313560D02*
Y315040D01*
X155684Y315500D01*
X157500D01*
X160500Y318500D01*
G01X155225Y309700D02*
X155324D01*
X157539Y307485D01*
X158915D01*
X160800Y305600D01*
X165900D01*
X166000Y305500D01*
G01X165200Y320575D02*
Y322356D01*
X165175Y322381D01*
Y322775D01*
X179700Y337300D01*
X181750D01*
G01X165200Y317425D02*
X161575D01*
X160500Y318500D01*
G01X158467Y344067D02*
X160580D01*
X161026Y343621D01*
G01Y346771D02*
X165026D01*
G01D02*
X169026D01*
G01X157925Y350500D02*
X156025Y348600D01*
X153000D01*
G01X163013Y405749D02*
Y408313D01*
X166600Y411900D01*
Y424660D01*
X166450Y424810D01*
G01X161120Y424590D02*
Y420080D01*
X164800Y416400D01*
Y412700D01*
X163670Y411570D01*
X161070D01*
X158013Y408513D01*
Y405749D01*
G01X153675Y432600D02*
Y429100D01*
X153575Y429000D01*
G01X153675Y432600D02*
Y441119D01*
X155390Y445260D01*
Y460256D01*
X156122Y462024D01*
Y466378D01*
G01X161450Y429425D02*
X162925D01*
X163630Y430130D01*
Y434530D01*
X164604Y435504D01*
X166909D01*
X167600Y436195D01*
Y437173D01*
X166909Y437864D01*
X163822D01*
X163131Y438555D01*
Y439533D01*
X163822Y440224D01*
X166909D01*
X167600Y440915D01*
Y441893D01*
X166909Y442584D01*
X163822D01*
X163131Y443275D01*
Y451419D01*
X165571Y457310D01*
Y465590D01*
G01X161450Y429425D02*
X159025Y427000D01*
X158001D01*
X156101Y425100D01*
G01X157600Y429425D02*
X156276D01*
X155464Y430237D01*
Y441360D01*
X156950Y444949D01*
Y450550D01*
X157500Y451100D01*
Y453390D01*
G01X159396Y449408D02*
X159400D01*
Y451000D01*
X160069Y451669D01*
X163209Y459250D01*
Y466378D01*
G01X157500Y453390D02*
Y459448D01*
X158484Y461824D01*
Y465590D01*
G01X182925Y92000D02*
X180600D01*
X179900Y91300D01*
G01X174600Y114000D02*
Y110775D01*
X178000Y107375D01*
G01Y104225D02*
Y103200D01*
X174460Y99660D01*
X171523D01*
G01X182000Y117200D02*
X181648Y117552D01*
Y120872D01*
X179810Y122710D01*
X178277D01*
X178186Y122801D01*
G01X172632Y123101D02*
X173578Y125384D01*
X174868Y126674D01*
X175752Y127040D01*
X176971D01*
X177584Y126786D01*
X179691D01*
X180151Y127246D01*
Y130861D01*
X181584Y132294D01*
X182103D01*
G01X184000Y134825D02*
X182103Y132928D01*
Y132294D01*
G01X188000Y134825D02*
X186725D01*
X184870Y132970D01*
Y128120D01*
X181510Y124760D01*
X180228D01*
X178269Y122801D01*
X178186D01*
G01X178284Y132394D02*
X177414D01*
X175580Y130560D01*
X173340D01*
X172710Y129930D01*
Y127090D01*
X171876Y125077D01*
X169900Y123101D01*
X168616D01*
G01X180000Y134725D02*
Y134110D01*
X178284Y132394D01*
G01X171900Y134825D02*
Y133190D01*
X170610Y131900D01*
G01X176000Y134725D02*
Y133958D01*
X174436Y132394D01*
G01X181595Y142905D02*
Y146694D01*
X183801Y148900D01*
X185817D01*
X190944Y154027D01*
Y156599D01*
X192500Y158155D01*
G01X180000Y137875D02*
Y141310D01*
X181595Y142905D01*
G01X176000Y137875D02*
Y140500D01*
G01X172890Y153260D02*
Y151030D01*
X174070Y149850D01*
Y143910D01*
X171900Y141740D01*
Y137975D01*
G01D02*
X171808Y137883D01*
X170186D01*
X170094Y137975D01*
X169723D01*
X169714Y137984D01*
X168091D01*
X168000Y138075D01*
G01X176752Y161304D02*
X175196Y159748D01*
G01X179902Y158155D02*
X178346Y156599D01*
G01X183051Y161304D02*
X181495Y159748D01*
G01X176752Y158155D02*
X175196Y156599D01*
G01X183051Y158155D02*
X181495Y156599D01*
G01X183051Y167603D02*
X181495Y166047D01*
G01Y153449D02*
X179939Y155005D01*
X179902D01*
G01X183051Y164454D02*
X181495Y162898D01*
G01X171700Y156900D02*
X173300Y158500D01*
Y159434D01*
X174409Y162111D01*
X176752Y164454D01*
G01X179902Y161304D02*
X178346Y159748D01*
G01X183051Y180202D02*
X181495Y178646D01*
G01X183051Y177052D02*
X181495Y175496D01*
G01X183051Y183351D02*
X181495Y181795D01*
G01X183051Y173903D02*
X181495Y172347D01*
G01X174569Y180202D02*
X176752D01*
G01X179902Y177052D02*
X178346Y175496D01*
G01X176752Y173903D02*
X175196Y172347D01*
G01X173000Y170200D02*
X176199D01*
X176752Y170753D01*
G01X183051D02*
X181495Y169197D01*
G01X183051Y186501D02*
X181495Y184945D01*
G01X183051Y189651D02*
X181495Y188095D01*
G01X179902Y189651D02*
X178346Y188095D01*
G01X176752Y199099D02*
X175196Y200655D01*
G01X179902Y208548D02*
X178346Y210104D01*
G01X181495Y203805D02*
X183051Y205361D01*
Y205399D01*
G01Y208548D02*
Y208511D01*
X181495Y206955D01*
G01X176752Y208548D02*
X175196Y210104D01*
G01X179902Y205399D02*
X178346Y206955D01*
G01X176752Y211698D02*
X175196Y213254D01*
G01X176752Y205399D02*
X175196Y206955D01*
G01X176752Y202249D02*
X175196Y203805D01*
G01X181495Y197506D02*
X183051Y199099D01*
G01X179902Y202249D02*
X178346Y203805D01*
G01X171836Y200655D02*
X170600Y201891D01*
Y209693D01*
X173570Y212663D01*
Y213486D01*
X173841Y214140D01*
X174260Y214559D01*
X174955Y214847D01*
X176752D01*
G01X171836Y198300D02*
X170100D01*
X168640Y199760D01*
Y209940D01*
X171663Y212963D01*
X172589Y215197D01*
X172873Y215481D01*
X173303Y215769D01*
X173829Y215987D01*
X175903Y216400D01*
X178349D01*
X179902Y214847D01*
G01X181495Y200655D02*
X183051Y202211D01*
Y202249D01*
G01Y217997D02*
X181495Y219553D01*
G01X183051Y224296D02*
X181495Y225852D01*
G01X183051Y221147D02*
X181495Y222703D01*
G01X174600Y217800D02*
X174797Y217997D01*
X176752D01*
G01X170400Y214700D02*
Y216525D01*
X172675Y218800D01*
X174608Y219600D01*
X178299D01*
X179902Y217997D01*
G01X183051Y214847D02*
X181495Y216403D01*
G01X176752Y221147D02*
X172847D01*
X172400Y220700D01*
G01X169967Y257386D02*
Y251045D01*
X171360Y247682D01*
X173842Y245200D01*
X178101D01*
X187757Y235544D01*
Y232188D01*
X189350Y230595D01*
G01X179902Y227446D02*
X178346Y229002D01*
G01X176752Y227446D02*
X175196Y229002D01*
G01X183051Y227446D02*
X181495Y229002D01*
G01X173992Y257386D02*
X171800Y255194D01*
Y250974D01*
X173054Y247945D01*
X174199Y246800D01*
X179101D01*
X188700Y237201D01*
Y234395D01*
X189350Y233745D01*
G01X183500Y245500D02*
X180891Y248109D01*
Y250336D01*
X178641Y252586D01*
X177413D01*
G01D02*
Y257185D01*
X178174Y257946D01*
G01Y261096D02*
X180011D01*
X180462Y260645D01*
Y258829D01*
X180458Y258825D01*
G01X173992Y260536D02*
X174392Y260936D01*
Y263104D01*
X174292Y263204D01*
Y263300D01*
G01X169967Y260536D02*
Y261687D01*
X171592Y263312D01*
G01X183325Y304200D02*
X179000D01*
X175900Y301100D01*
X168300D01*
G01X175925Y329200D02*
X173499D01*
X167500Y323201D01*
Y312500D01*
G01D02*
Y310300D01*
X169100Y308700D01*
Y308677D01*
X169077D01*
G01X175925Y325200D02*
X173600Y322875D01*
Y314739D01*
X172050Y313189D01*
Y308120D01*
X170561Y306631D01*
G01X179075Y325200D02*
Y329200D01*
G01D02*
X180255Y330380D01*
X186581D01*
X194401Y338200D01*
X197587D01*
G01X183800Y345400D02*
X184300Y344900D01*
X184301D01*
X185000Y344201D01*
Y338500D01*
X183800Y337300D01*
X181750D01*
G01X178300Y348600D02*
X175400Y345700D01*
Y344399D01*
X174622Y343621D01*
X173026D01*
G01X168013Y365197D02*
Y359587D01*
X171552Y351043D01*
Y349163D01*
X169160Y346771D01*
X169026D01*
G01X173013Y365197D02*
Y356887D01*
X174700Y355200D01*
Y348445D01*
X173026Y346771D01*
G01X178300Y348600D02*
Y352621D01*
X179021Y353342D01*
X183749D01*
X184470Y354063D01*
Y355081D01*
X183749Y355802D01*
X179021D01*
X178300Y356523D01*
Y362142D01*
X180845Y364687D01*
X189050D01*
X189800Y365437D01*
Y366497D01*
X189050Y367247D01*
X183650D01*
X182900Y367997D01*
Y369057D01*
X183650Y369807D01*
X189050D01*
X189800Y370557D01*
Y371617D01*
X189050Y372367D01*
X174650D01*
X173800Y373217D01*
Y374277D01*
X174450Y374927D01*
X189050D01*
X189800Y375677D01*
Y380399D01*
X188399Y381800D01*
X176280D01*
X174781Y383299D01*
Y387650D01*
X174031Y388400D01*
X172971D01*
X172221Y387650D01*
Y382950D01*
X171471Y382200D01*
X170411D01*
X169661Y382950D01*
Y391810D01*
X170121Y392270D01*
X190100D01*
G01X191843Y403995D02*
X188919D01*
X186864Y406050D01*
Y409710D01*
X190055Y412901D01*
X194723D01*
X195300Y413478D01*
Y414294D01*
X194723Y414871D01*
X193077D01*
X192500Y415448D01*
Y416962D01*
X192040Y417422D01*
X191018D01*
X189378Y415782D01*
X188318D01*
X187567Y416533D01*
Y417593D01*
X188811Y418837D01*
Y419489D01*
X187182Y421118D01*
Y422456D01*
X188837Y424111D01*
Y424763D01*
X187817Y425783D01*
X187165D01*
X185371Y423989D01*
X183528D01*
X182951Y423412D01*
Y398477D01*
X182374Y397900D01*
X181558D01*
X180981Y398477D01*
Y399981D01*
X180404Y400558D01*
X177677D01*
X177100Y401135D01*
Y401951D01*
X177677Y402528D01*
X180404D01*
X180981Y403105D01*
Y403921D01*
X180404Y404498D01*
X177677D01*
X177100Y405075D01*
Y405891D01*
X177677Y406468D01*
X180404D01*
X180981Y407045D01*
Y408966D01*
X180404Y409543D01*
X174457D01*
X173708Y410292D01*
Y410944D01*
X174277Y411513D01*
X180404D01*
X180981Y412090D01*
Y412906D01*
X180404Y413483D01*
X174277D01*
X173700Y414060D01*
Y414876D01*
X174277Y415453D01*
X180404D01*
X180981Y416030D01*
Y416846D01*
X180404Y417423D01*
X174277D01*
X173700Y418000D01*
Y418816D01*
X174277Y419393D01*
X180404D01*
X180981Y419970D01*
Y422808D01*
X179800Y423989D01*
G01X171276Y423621D02*
X169721D01*
X168600Y422500D01*
Y419262D01*
X169350Y418512D01*
X171440D01*
X171900Y418052D01*
Y416412D01*
X171440Y415952D01*
X168560D01*
X168100Y415492D01*
Y410411D01*
X168611Y409900D01*
X171200D01*
X173013Y408087D01*
Y405749D01*
G01X177575Y432600D02*
X181225D01*
X181400Y432775D01*
G01X169600Y432670D02*
X171270D01*
X173600Y435000D01*
X176199D01*
X177575Y433624D01*
Y432600D01*
G01X168029Y456660D02*
Y445333D01*
X169808Y441039D01*
X170535Y437381D01*
X169598Y432673D01*
X169600Y432670D01*
G01X171276Y423621D02*
X171481Y423416D01*
X175009D01*
X175100Y423325D01*
G01Y426475D02*
X177314D01*
X179800Y423989D01*
G01X168029Y456660D02*
X167933Y456756D01*
Y465590D01*
G01X171400Y450600D02*
X170294Y451706D01*
X170295Y457041D01*
Y466378D01*
G01X197111Y92326D02*
X192925D01*
X190912Y90313D01*
G01D02*
X188599Y88000D01*
X186075D01*
G01Y96000D02*
Y92000D01*
G01X197111Y96066D02*
X191100D01*
G01D02*
X186141D01*
X186075Y96000D01*
G01X200900Y110800D02*
X195875D01*
X195375Y111300D01*
G01X186891Y113991D02*
X189581Y111300D01*
X192225D01*
G01X190744Y114456D02*
X191975Y113225D01*
X196024D01*
X198110Y115311D01*
Y119075D01*
X198960Y119925D01*
X200000D01*
G01X187069Y116800D02*
X187811D01*
X189500Y118489D01*
Y122230D01*
X190371Y123101D01*
X191400D01*
G01X184729Y115820D02*
X184100Y116449D01*
Y117494D01*
X183800Y117794D01*
Y119925D01*
G01X192000Y134825D02*
X189600Y132425D01*
Y127401D01*
X191400Y125601D01*
Y123101D01*
G01X195983Y132294D02*
Y134794D01*
G01X196065Y123101D02*
X193903Y125263D01*
Y130214D01*
X195983Y132294D01*
G01X183800Y123075D02*
X186199Y125474D01*
Y125599D01*
X186200Y125600D01*
G01X184000Y137975D02*
Y140500D01*
G01X188000Y137975D02*
X186800Y139175D01*
Y142800D01*
G01D02*
Y144900D01*
X194059Y152159D01*
Y156564D01*
X195650Y158155D01*
G01X192194Y142712D02*
Y147860D01*
X195650Y151316D01*
Y155005D01*
G01X192194Y142712D02*
Y140112D01*
X192000Y139918D01*
Y137975D01*
G01X195983Y137944D02*
X194591Y139336D01*
Y147138D01*
X197679Y150226D01*
Y153885D01*
X198799Y155005D01*
G01X186201Y167603D02*
X184645Y166047D01*
G01X195650Y164454D02*
X194094Y162898D01*
G01X195650Y161304D02*
X194094Y159748D01*
G01X184645Y156599D02*
X183051Y155005D01*
G01X189350Y164454D02*
X187794Y162898D01*
G01X189350Y167603D02*
X187794Y166047D01*
G01X186201Y164454D02*
X184645Y162898D01*
G01X186201Y161304D02*
X184645Y159748D01*
G01X190944Y162898D02*
X189350Y161304D01*
G01X192500D02*
X190944Y159748D01*
G01X189350Y155005D02*
X187794Y153449D01*
G01X192500Y155005D02*
Y152904D01*
X192400Y152804D01*
G01X195650Y167603D02*
X194094Y166047D01*
G01X186201Y155005D02*
X184645Y153449D01*
G01X190944Y166047D02*
X192500Y164491D01*
Y164454D01*
G01X189350Y158155D02*
X187794Y156599D01*
G01X189350Y180202D02*
X187794Y178646D01*
G01X186201Y183351D02*
X184645Y181795D01*
G01X189350Y177052D02*
X187794Y175496D01*
G01X186201Y180202D02*
X184645Y178646D01*
G01X186201Y177052D02*
X184645Y175496D01*
G01X190944Y169197D02*
X192500Y167641D01*
Y167603D01*
G01X189350Y173903D02*
X187794Y172347D01*
G01X186201Y170753D02*
X184645Y169197D01*
G01X186201Y173903D02*
X184645Y172347D01*
G01X189350Y170753D02*
X187794Y169197D01*
G01X184645Y197506D02*
X186201Y195950D01*
G01Y186501D02*
X184645Y184945D01*
G01X186201Y199099D02*
X184645Y200655D01*
G01X186201Y202249D02*
X184645Y203805D01*
G01X187794Y210104D02*
X186201Y211697D01*
Y211698D01*
G01X184645Y213254D02*
X183089Y211698D01*
X183051D01*
G01X195650Y221147D02*
X194094Y222703D01*
G01X195650Y224296D02*
X194094Y225852D01*
G01X187794D02*
X190944D01*
X192500Y224296D01*
G01X187794Y219553D02*
Y216440D01*
X186201Y214847D01*
G01X189350Y224296D02*
X190944Y222702D01*
G01X186201Y217997D02*
X184645Y219553D01*
G01X186201Y224296D02*
X184645Y225852D01*
G01X189350Y221147D02*
X187794Y222703D01*
G01X186201Y221147D02*
X184645Y222703D01*
G01X192500Y221147D02*
X194094Y219553D01*
G01X190708Y245541D02*
X193124Y243125D01*
X196676D01*
X198700Y241101D01*
Y239500D01*
X195650Y236450D01*
Y233745D01*
G01X187794Y229002D02*
X189829D01*
X191732Y228214D01*
X192500Y227446D01*
G01Y230595D02*
X190959Y232136D01*
Y234327D01*
X189800Y235486D01*
Y239200D01*
X183500Y245500D01*
G01X183413Y253286D02*
Y253086D01*
X183588Y252911D01*
X186788D01*
X187379Y252320D01*
X187383Y252311D01*
X188627Y251067D01*
Y248805D01*
X187946Y248124D01*
Y244754D01*
X193493Y239207D01*
Y234738D01*
X192500Y233745D01*
G01X186201Y227446D02*
X184645Y229002D01*
G01X190708Y245541D02*
Y247308D01*
X191538Y248138D01*
Y250261D01*
G01X201949Y233745D02*
Y239773D01*
X196170Y245552D01*
G01D02*
Y250771D01*
X198070Y252671D01*
Y254189D01*
X197145Y255114D01*
Y260830D01*
G01X183350Y259205D02*
Y257579D01*
X183411Y257518D01*
Y255499D01*
X183413Y255497D01*
Y253286D01*
G01X187400Y255700D02*
X186800Y256300D01*
Y257399D01*
X187550Y258149D01*
Y259665D01*
G01X199810Y253361D02*
Y254990D01*
X198800Y256000D01*
Y263085D01*
X197075Y264810D01*
G01D02*
X197385Y265120D01*
X201100D01*
G01X188500Y274900D02*
X190854D01*
X193130Y272624D01*
Y269398D01*
X193386Y269142D01*
G01X184200Y264900D02*
Y263205D01*
X183350Y262355D01*
G01X186925Y267000D02*
Y263440D01*
X187550Y262815D01*
G01X185000Y270700D02*
Y267500D01*
X185500Y267000D01*
X186925D01*
G01X192500Y278000D02*
X194772Y275728D01*
X202535D01*
X202993Y275270D01*
X204429D01*
X205575Y274124D01*
Y273000D01*
G01X196443Y294065D02*
X196462Y294046D01*
X203173D01*
X209500Y287719D01*
Y276075D01*
G01X186475Y300200D02*
X191199D01*
G01X197012Y299320D02*
X192079D01*
X191199Y300200D01*
G01X191230Y305500D02*
X192192D01*
X195812Y301880D01*
X197012D01*
G01X186475Y304200D02*
X186575D01*
X187875Y305500D01*
X191230D01*
G01X208413Y328200D02*
X207183Y326970D01*
X193870D01*
X191800Y324900D01*
Y324692D01*
X188083Y320975D01*
X188000D01*
G01X199750Y361100D02*
X197020D01*
X196595Y360675D01*
X195556D01*
X195464Y360767D01*
X193842D01*
X193750Y360675D01*
G01Y368175D02*
Y363825D01*
G01Y368175D02*
X192834D01*
X191500Y369509D01*
Y384560D01*
X190050Y386010D01*
Y389140D01*
G01X199595Y378154D02*
X198174Y379575D01*
X193750D01*
G01X203595Y386954D02*
X201974Y388575D01*
X193750D01*
G01X202674Y404600D02*
Y400777D01*
X202277Y400380D01*
X199188D01*
X197804Y398996D01*
X196056D01*
X195386Y399666D01*
Y400332D01*
X196730Y401676D01*
Y403524D01*
X192700Y407554D01*
Y409075D01*
X194589Y410964D01*
X196677D01*
X197770Y409871D01*
Y406297D01*
X198718Y404008D01*
X199880Y402846D01*
G01X192334Y432327D02*
X195300D01*
G01X192334D02*
Y443140D01*
X194400Y448127D01*
Y453128D01*
X195720Y454448D01*
Y456976D01*
X197300Y458556D01*
Y460528D01*
X197700Y460928D01*
Y465396D01*
X197894Y465590D01*
G01X200256Y466378D02*
X199900Y466022D01*
Y462054D01*
X199700Y461854D01*
Y458184D01*
X197680Y456164D01*
Y453636D01*
X196800Y452756D01*
Y446690D01*
X195900Y445790D01*
Y444734D01*
X198500Y442134D01*
Y439240D01*
X196444Y437184D01*
Y433989D01*
X196600Y433833D01*
Y433799D01*
X197260Y433139D01*
Y431515D01*
X196112Y430367D01*
X196100D01*
Y425600D01*
X198000Y423700D01*
Y420700D01*
X200048Y418652D01*
G01X185000Y454000D02*
X186700D01*
X187700Y455000D01*
Y461201D01*
X188451Y461952D01*
Y465584D01*
X188445Y465590D01*
G01X185000Y456500D02*
Y460701D01*
X186083Y461784D01*
Y466378D01*
G01X191780Y453300D02*
X191800D01*
X193760Y455260D01*
Y457788D01*
X195300Y459328D01*
Y461300D01*
X195532Y461532D01*
Y465590D01*
G01X191780Y456700D02*
Y458580D01*
X193300Y460100D01*
Y466247D01*
X193169Y466378D01*
G01X211142Y24764D02*
X211000Y24906D01*
Y40925D01*
G01X212872Y48793D02*
X211000Y46921D01*
Y44075D01*
G01X206200Y102200D02*
X204500D01*
X203000Y100700D01*
Y96800D01*
X203734Y96066D01*
X205969D01*
G01X206200Y102200D02*
X210200D01*
X210600Y101800D01*
X214131D01*
X214345Y102014D01*
G01X200900Y110800D02*
X202400Y112300D01*
Y112731D01*
X206605Y116936D01*
Y138229D01*
X206958Y139081D01*
X207640Y139763D01*
Y145102D01*
X206171Y148650D01*
Y152414D01*
X205098Y155005D01*
G01X198703Y143302D02*
Y139703D01*
X198000Y139000D01*
Y125075D01*
X200000Y123075D01*
G01X199985Y134794D02*
Y132294D01*
G01X210189Y123101D02*
X211700D01*
X214932Y126333D01*
Y131132D01*
X216094Y132294D01*
X217262D01*
G01X212757Y134794D02*
X211468D01*
X210710Y134036D01*
Y130290D01*
X211346Y129654D01*
X212727D01*
G01X208627Y134794D02*
Y132394D01*
G01X204000Y123075D02*
X202524D01*
X202000Y123599D01*
Y131834D01*
X202460Y132294D01*
X204120D01*
G01D02*
Y134794D01*
G01X211490Y143700D02*
Y145109D01*
X208248Y148351D01*
Y155005D01*
G01X211490Y143700D02*
X209800D01*
X209300Y143200D01*
Y138617D01*
X208627Y137944D01*
G01X199985D02*
X201318Y139277D01*
Y148317D01*
X201949Y148948D01*
Y155005D01*
G01X198703Y143302D02*
Y148446D01*
X200379Y150122D01*
Y156585D01*
X201949Y158155D01*
G01X204120Y137944D02*
X203648Y138416D01*
Y143252D01*
X203703Y143307D01*
G01D02*
X203648Y143362D01*
Y147528D01*
X204120Y148000D01*
Y152580D01*
X203480Y153220D01*
Y156537D01*
X205098Y158155D01*
G01X211398Y161304D02*
X209842Y159748D01*
G01X208248Y158155D02*
X206692Y156599D01*
G01X205098Y167603D02*
X203542Y166047D01*
G01X208248Y164454D02*
X206692Y162898D01*
G01X205098Y164454D02*
X203542Y162898D01*
G01X201949Y161304D02*
X200393Y159748D01*
G01X211398Y167603D02*
X209842Y166047D01*
G01X198799Y167603D02*
X197243Y166047D01*
G01X198799Y161304D02*
X197243Y159748D01*
G01X198799Y164454D02*
X197243Y162898D01*
G01X211398Y164454D02*
X209842Y162898D01*
G01X201949Y164454D02*
X200393Y162898D01*
G01X205098Y161304D02*
X203542Y159748D01*
G01X201949Y167603D02*
X200393Y166047D01*
G01X211398Y155005D02*
X209842Y153449D01*
G01X208248Y167603D02*
X206692Y166047D01*
G01X208248Y161304D02*
X206692Y159748D01*
G01X211398Y170753D02*
X209842Y169197D01*
G01X211398Y224296D02*
X209842Y225852D01*
G01X198799Y221147D02*
X197243Y222703D01*
G01X208248Y217997D02*
X206692Y219553D01*
G01X205098Y224296D02*
X203542Y225852D01*
G01X205098Y217997D02*
X203542Y219553D01*
G01X208248Y221147D02*
X206692Y222703D01*
G01X211398Y221147D02*
X209842Y222703D01*
G01X208248Y224296D02*
X206692Y225852D01*
G01X201949Y227446D02*
X200393Y229002D01*
G01X205098Y227446D02*
X203542Y229002D01*
G01X211398Y233745D02*
X209746Y235397D01*
G01X199810Y250211D02*
X201000Y249021D01*
Y247199D01*
X200200Y246399D01*
Y244040D01*
X206200Y238040D01*
Y235793D01*
X208248Y233745D01*
G01X214547D02*
X214355D01*
X202600Y245500D01*
G01X210715Y244900D02*
Y240727D01*
X217697Y233745D01*
G01X211398Y230595D02*
X209842Y232151D01*
G01X208248Y230595D02*
X206692Y232151D01*
G01X208248Y227446D02*
X206692Y229002D01*
G01X211398Y227446D02*
X209842Y229002D01*
G01X206440Y261171D02*
X207400Y260211D01*
Y256585D01*
X206200Y255385D01*
G01X200680Y257540D02*
Y256744D01*
X204063Y253361D01*
G01X202600Y245500D02*
Y247409D01*
X204063Y248872D01*
Y250211D01*
G01X207912Y253199D02*
X208089Y253273D01*
X209644Y257021D01*
Y264769D01*
X208020Y268690D01*
Y270555D01*
X205575Y273000D01*
G01X207912Y250049D02*
X208500Y249461D01*
Y247100D01*
X209400Y246200D01*
Y245900D01*
X210400Y244900D01*
X210715D01*
G01X206051Y247911D02*
Y246414D01*
X207565Y244900D01*
G01X206440Y261171D02*
X204362Y262030D01*
X202303Y266997D01*
X201255Y268045D01*
X200330D01*
X199675Y268700D01*
G01X213000Y250500D02*
Y258102D01*
X211304Y259798D01*
Y262804D01*
X214000Y265500D01*
Y268425D01*
X209500Y272925D01*
G01X261300Y253375D02*
Y255916D01*
X262736Y257352D01*
X263552D01*
X265494Y255410D01*
X266310D01*
X266888Y255988D01*
Y256804D01*
X264254Y259438D01*
Y260254D01*
X264832Y260832D01*
X265648D01*
X268932Y257548D01*
X269683D01*
X270326Y258191D01*
Y258942D01*
X267734Y261534D01*
Y262350D01*
X268312Y262928D01*
X269128D01*
X271720Y260336D01*
X272471D01*
X273114Y260979D01*
Y261730D01*
X270522Y264322D01*
Y265138D01*
X271100Y265716D01*
X271916D01*
X273858Y263774D01*
X274674D01*
X275252Y264352D01*
Y265168D01*
X273310Y267110D01*
Y267926D01*
X275200Y269816D01*
Y277346D01*
X277567Y279713D01*
Y280421D01*
X272804Y285184D01*
Y298248D01*
X268322Y302730D01*
X265276D01*
X263674Y301128D01*
Y296977D01*
X263097Y296400D01*
X262281D01*
X261704Y296977D01*
Y300993D01*
X261127Y301570D01*
X258570D01*
X254558Y297558D01*
X252642D01*
X251336Y298864D01*
Y301164D01*
X249900Y302600D01*
X239954D01*
X239324Y301970D01*
X238570D01*
X225105Y288505D01*
X222748D01*
X220353Y290900D01*
X210600D01*
X202330Y299170D01*
Y304430D01*
X204515Y306615D01*
X211885D01*
X211955Y306545D01*
X214509D01*
X216384Y308420D01*
Y312216D01*
G01X210988Y296565D02*
X216035D01*
X217400Y295200D01*
G01X217673Y300600D02*
X216393Y299320D01*
X210988D01*
G01X220600Y317925D02*
X219825Y318700D01*
X214500D01*
X213800Y318000D01*
X208200D01*
X207100Y316900D01*
Y309700D01*
X205800Y308400D01*
X204100D01*
X200800Y305100D01*
Y298300D01*
X210000Y289100D01*
X220000D01*
X222300Y286800D01*
Y282175D01*
G01X210789Y313600D02*
X212600D01*
X213446Y314446D01*
X220249D01*
X221260Y313435D01*
G01X220600Y321075D02*
X219725Y320200D01*
X213300D01*
X212600Y319500D01*
X205900D01*
X205400Y319000D01*
Y316700D01*
X204859Y316159D01*
X203211D01*
G01X218100Y305600D02*
Y304600D01*
X215380Y301880D01*
X210988D01*
G01X197587Y338200D02*
X204100D01*
X211000Y331300D01*
X220500D01*
X223900Y327900D01*
Y316075D01*
X221260Y313435D01*
G01X208413Y348200D02*
X219981D01*
X224101Y352320D01*
G01X199595Y378154D02*
X203750Y373999D01*
Y369900D01*
G01X213500Y379575D02*
X212375D01*
X211400Y378600D01*
Y375190D01*
X209450Y373240D01*
X208000D01*
G01X213500Y385925D02*
X211504D01*
X210475Y386954D01*
X203595D01*
G01X200222Y398150D02*
X202964D01*
X203441Y397673D01*
Y394877D01*
X203858Y394460D01*
X204994D01*
X205411Y394877D01*
Y397473D01*
X206088Y398150D01*
X208300D01*
G01D02*
X208551D01*
X212290Y401889D01*
Y407329D01*
X211560Y408059D01*
Y428985D01*
X211700Y429125D01*
G01X202674Y404600D02*
Y408423D01*
X203448Y409197D01*
X204156D01*
X205144Y408209D01*
Y401360D01*
X205604Y400900D01*
X209196D01*
X210809Y402513D01*
Y406291D01*
X209769Y407331D01*
Y416731D01*
X206900Y419600D01*
X206725D01*
G01X200048Y418652D02*
X200200Y418500D01*
Y414330D01*
X203070Y411460D01*
X204765D01*
X207539Y408686D01*
G01X209875Y419600D02*
X208830Y422124D01*
Y424500D01*
G01X207300Y429125D02*
X205447Y427272D01*
X204035D01*
X202700Y425937D01*
Y420600D01*
X207278Y416022D01*
G01X203400Y432275D02*
Y433913D01*
X202513Y434800D01*
G01X207343Y466378D02*
X207000Y466035D01*
Y461100D01*
X206000Y460100D01*
Y451572D01*
X203240Y448812D01*
Y444360D01*
X204900Y442700D01*
Y437187D01*
X202513Y434800D01*
G01X204980Y465590D02*
X204525Y465135D01*
Y461525D01*
X203790Y460790D01*
Y452134D01*
X201280Y449624D01*
Y443476D01*
X201854Y442902D01*
Y438249D01*
X198405Y434800D01*
G01D02*
X199405Y433800D01*
Y432327D01*
G01X207300Y432275D02*
X207430Y432405D01*
Y447230D01*
X215434Y455234D01*
X216975Y457539D01*
X217230Y458156D01*
Y459044D01*
X216858Y459942D01*
X214900Y461900D01*
Y465907D01*
X214429Y466378D01*
G01X211700Y432275D02*
Y433800D01*
X213900Y436000D01*
G01X208830Y424500D02*
X209600Y440178D01*
Y445266D01*
X209720Y445870D01*
X209890Y446279D01*
X210073Y446553D01*
X210165Y446665D01*
X215649Y452716D01*
X218276Y456864D01*
X218800Y458130D01*
Y459069D01*
X217929Y461172D01*
X217410Y461691D01*
X217200Y462198D01*
Y465181D01*
X216791Y465590D01*
G01X199000Y444500D02*
Y449993D01*
X200207Y452907D01*
X201830Y454530D01*
Y461613D01*
X202200Y461983D01*
Y465172D01*
X202618Y465590D01*
G01X205200Y445400D02*
Y448000D01*
X211800Y454600D01*
Y458400D01*
X209705Y460495D01*
Y465590D01*
G01X215000Y40925D02*
X219000D01*
G01X215000Y44075D02*
Y46665D01*
X212872Y48793D01*
G01X216400Y106400D02*
X219728D01*
X220564Y107236D01*
G01X216400Y106400D02*
Y108316D01*
X215949Y108767D01*
X214785D01*
G01X214345Y102014D02*
Y97984D01*
G01X280270Y88470D02*
Y88280D01*
X279570Y87580D01*
X269180D01*
X266700Y85100D01*
X249631D01*
X236971Y97760D01*
X226370D01*
X222890Y101240D01*
G01X223300Y119925D02*
Y117400D01*
G01X225284Y132294D02*
Y134794D01*
G01X214464Y123101D02*
X218463Y127100D01*
X221899D01*
X223110Y128311D01*
Y130120D01*
X225284Y132294D01*
G01X217262D02*
Y134794D01*
G01X221278D02*
Y132294D01*
G01X225300Y125200D02*
Y123525D01*
X224850Y123075D01*
X223300D01*
G01X217697Y155005D02*
X218677D01*
X220719Y152963D01*
Y150281D01*
X224784Y146216D01*
Y142600D01*
G01D02*
Y138444D01*
X225284Y137944D01*
G01X223996Y155005D02*
Y151804D01*
X229396Y146404D01*
Y137944D01*
G01X219800Y143250D02*
Y145100D01*
X215987Y148913D01*
Y151714D01*
X214547Y153154D01*
Y155005D01*
G01X217262Y137944D02*
X219800Y140482D01*
Y143250D01*
G01X221278Y137944D02*
X222200Y138866D01*
Y145701D01*
X218574Y149327D01*
Y151913D01*
X216102Y154385D01*
Y156600D01*
X214547Y158155D01*
G01Y161304D02*
X212991Y159748D01*
Y147109D01*
X214814Y145286D01*
Y142700D01*
G01D02*
Y140001D01*
X212757Y137944D01*
G01X228600Y123075D02*
Y127100D01*
X227500Y128200D01*
Y145901D01*
X222373Y151028D01*
Y153478D01*
X220846Y155005D01*
G01X223996Y161304D02*
X225552Y159748D01*
G01X220846Y164454D02*
X222402Y162898D01*
G01X217697Y167603D02*
X219253Y166047D01*
G01X223996Y164454D02*
X225552Y162898D01*
G01X223996Y167603D02*
X225552Y166047D01*
G01X220846Y167603D02*
X222402Y166047D01*
G01X217697Y161304D02*
X219253Y159748D01*
G01X220846Y161304D02*
X222402Y159748D01*
G01X214547Y164454D02*
X212991Y162898D01*
G01X217697Y164454D02*
X219253Y162898D01*
G01X217697Y158155D02*
X219253Y156599D01*
G01X220846Y158155D02*
X222402Y156599D01*
G01X214547Y167603D02*
X212991Y166047D01*
G01X227146Y155005D02*
X225658Y153369D01*
G01X223996Y170753D02*
X225552Y169197D01*
G01X217697Y170753D02*
X219253Y169197D01*
G01X217697Y221147D02*
X216141Y222703D01*
G01X214547Y224296D02*
X212991Y222740D01*
G01X227146Y221147D02*
X225590Y222703D01*
Y222720D01*
G01X214547Y221147D02*
X216103Y219591D01*
G01X217697Y217997D02*
X219253Y219553D01*
G01X227146Y224296D02*
X225590Y225852D01*
G01X223996Y221147D02*
X222440Y222703D01*
G01X223996Y217997D02*
X225552Y219553D01*
G01X220846Y217997D02*
X222402Y219553D01*
G01X223996Y224296D02*
X222440Y225852D01*
G01X212991Y225890D02*
X216103D01*
X217697Y224296D01*
G01X220846D02*
X219290Y225852D01*
G01X220846Y221147D02*
X219290Y222703D01*
G01X218200Y249025D02*
Y245982D01*
X217400Y244050D01*
Y240800D01*
X218900Y239300D01*
X220894D01*
X222371Y237823D01*
Y234384D01*
X222376Y234379D01*
Y233111D01*
X222371Y233106D01*
Y232120D01*
X220846Y230595D01*
G01X213000Y250500D02*
Y248440D01*
X212800Y247959D01*
Y241791D01*
X220846Y233745D01*
G01X225195Y258930D02*
Y256206D01*
X227500Y253901D01*
Y250076D01*
X227049Y249625D01*
X225700D01*
X223180Y247105D01*
Y242170D01*
X225546Y239804D01*
Y232145D01*
X223996Y230595D01*
G01Y227446D02*
X225552Y229002D01*
G01X214547Y227446D02*
X212991Y229002D01*
G01X214547Y230595D02*
X212991Y232151D01*
G01X221800Y249025D02*
Y247899D01*
X220307Y246406D01*
X218960Y243154D01*
Y241447D01*
X219507Y240900D01*
X221501D01*
X223986Y238415D01*
Y236707D01*
X223996Y236697D01*
Y233745D01*
G01X220846Y227446D02*
X222402Y229002D01*
G01X217697Y227446D02*
X219253Y229002D01*
G01X215500Y247111D02*
Y247211D01*
X216400Y248111D01*
Y251043D01*
X216957Y251600D01*
X217625D01*
X218200Y252175D01*
G01X231900Y272700D02*
X231060Y271860D01*
Y271460D01*
X228300Y268700D01*
X225154D01*
X218800Y262346D01*
Y257001D01*
X221800Y254001D01*
Y252175D01*
G01X225275Y246000D02*
Y244380D01*
X227146Y242509D01*
Y233745D01*
G01X222045Y258930D02*
Y260880D01*
X222833Y261668D01*
G01X222300Y279025D02*
Y277200D01*
X226500Y273000D01*
G01X217400Y295200D02*
X221525D01*
X222925Y296600D01*
G01Y300600D02*
X217673D01*
G01X222925Y304600D02*
X221925Y305600D01*
X218100D01*
G01X226075Y304600D02*
Y309390D01*
G01D02*
X225180Y310285D01*
X221260D01*
G01X228300Y319400D02*
Y322865D01*
X226100Y325065D01*
G01X220600Y321075D02*
Y324725D01*
G01X225650Y337520D02*
Y336040D01*
X226615Y335075D01*
X228500D01*
G01Y347875D02*
X225075D01*
X221000Y343800D01*
G01X231500Y352500D02*
X230500Y353500D01*
X226859D01*
X224559Y355800D01*
X216800D01*
X213700Y358900D01*
Y363100D01*
G01X255165Y363606D02*
X249712D01*
X248991Y364327D01*
Y367369D01*
X248270Y368090D01*
X247252D01*
X246531Y367369D01*
Y364327D01*
X245810Y363606D01*
X244933D01*
X241200Y362060D01*
X232640D01*
X228780Y358200D01*
X222400D01*
X219800Y360800D01*
Y364200D01*
G01X213500Y376425D02*
Y373700D01*
X213490Y373690D01*
G01X213700Y363100D02*
X213490Y363310D01*
Y373690D01*
G01X226710Y364815D02*
X226715D01*
Y372400D01*
G01X238551Y369512D02*
X229361D01*
X228500Y370373D01*
Y371799D01*
X227899Y372400D01*
X226715D01*
G01X220975Y416000D02*
X226172D01*
X230000Y412172D01*
Y398200D01*
X226400Y394600D01*
X220200D01*
X216800Y391200D01*
Y373848D01*
X217521Y373127D01*
X220189D01*
X220910Y372406D01*
Y371388D01*
X220189Y370667D01*
X217521D01*
X216800Y369946D01*
Y367200D01*
X219800Y364200D01*
G01X238551Y373449D02*
X234050D01*
X228114Y379385D01*
X226650D01*
G01X213500Y385925D02*
Y379575D01*
G01X238551Y377386D02*
X236363D01*
X234569Y379180D01*
X230785D01*
X226705Y383260D01*
G01X222800Y376200D02*
X226615D01*
X226650Y376235D01*
G01X235370Y403500D02*
Y400470D01*
X227840Y392940D01*
X220888D01*
X218620Y390672D01*
Y379480D01*
X221900Y376200D01*
X222800D01*
G01X226650Y376235D02*
X228365D01*
X230287Y374313D01*
Y373100D01*
G01X222986Y400323D02*
X226388Y403725D01*
X226500D01*
G01X213200Y399166D02*
X213750Y399716D01*
Y407934D01*
X213020Y408664D01*
Y423542D01*
X215256Y428941D01*
X215700Y429125D01*
G01X226500Y406875D02*
X226428Y406947D01*
Y411600D01*
G01D02*
X223788Y414240D01*
X218460D01*
X217825Y414875D01*
Y416000D01*
G01D02*
X216894Y416931D01*
X216600Y417641D01*
Y422330D01*
X216820Y422862D01*
X217027Y423364D01*
X218243Y424580D01*
X218281D01*
X221360Y427659D01*
Y434607D01*
X221362Y434611D01*
X223572Y436821D01*
X226300Y443412D01*
Y465530D01*
X226240Y465590D01*
G01X219250Y422150D02*
X223170Y426070D01*
Y433859D01*
X225108Y435797D01*
X228250Y443383D01*
Y455550D01*
X230965Y458265D01*
Y465590D01*
G01X223878D02*
X223884Y465584D01*
Y462016D01*
X225200Y460700D01*
Y454300D01*
X221800Y450900D01*
Y448500D01*
X223860Y446440D01*
Y441858D01*
X222163Y437760D01*
X219954Y435551D01*
X219600Y434697D01*
Y432275D01*
G01X215700D02*
X217100Y433675D01*
Y436100D01*
G01X213900Y436000D02*
X214900Y437000D01*
Y439240D01*
X215360Y439700D01*
X217359D01*
X220400Y442741D01*
Y446200D01*
X219070Y447530D01*
Y451870D01*
X220300Y453100D01*
Y461100D01*
X219600Y461800D01*
Y465144D01*
X219154Y465590D01*
G01X217100Y436100D02*
X220737Y439737D01*
X221860Y442447D01*
Y446840D01*
X220740Y447960D01*
Y451439D01*
X221755Y452454D01*
X224100Y458116D01*
Y459700D01*
X221900Y461900D01*
Y465994D01*
X221516Y466378D01*
G01X237000Y41425D02*
X237717Y40708D01*
Y24764D01*
G01X233000Y41425D02*
X237000D01*
G01X234600Y107925D02*
Y106020D01*
X235630Y104990D01*
G01X228832Y113732D02*
Y111168D01*
X229500Y110500D01*
X231592D01*
G01D02*
X231892D01*
X232467Y111075D01*
X234600D01*
G01X230293Y117417D02*
X229300Y118410D01*
Y119225D01*
X228600Y119925D01*
G01X243700Y109175D02*
Y112500D01*
X241900Y114300D01*
G01X239206Y112300D02*
X241206Y114300D01*
X241900D01*
G01X229396Y137944D02*
X230556D01*
X231500Y137000D01*
Y131482D01*
X231181Y131163D01*
Y128320D01*
X233000Y126501D01*
Y123500D01*
X233400Y123100D01*
G01D02*
X238381D01*
X238382Y123101D01*
G01X229396Y134794D02*
Y132294D01*
G01X242200Y123075D02*
Y124501D01*
X240494Y126207D01*
X239600Y128366D01*
Y145032D01*
X231832Y152800D01*
Y156580D01*
X231851Y156599D01*
G01X242195Y141003D02*
X242723Y141531D01*
Y145039D01*
X237100Y150662D01*
Y153388D01*
X236594Y153894D01*
Y155005D01*
G01X232384Y148884D02*
X230625Y150643D01*
Y154208D01*
X230295Y155005D01*
G01X237655Y137944D02*
Y141684D01*
X236290Y144978D01*
X232384Y148884D01*
G01X227700Y151900D02*
X228700Y152900D01*
Y156601D01*
X227146Y158155D01*
G01X233511Y138144D02*
Y142983D01*
G01D02*
X232262Y145997D01*
X227700Y150559D01*
Y151900D01*
G01X227146Y164454D02*
X228702Y162898D01*
G01X236594Y164454D02*
X238150Y162898D01*
G01X227146Y161304D02*
X228702Y159748D01*
G01X227146Y167603D02*
X228702Y166047D01*
G01X236594Y158155D02*
X238150Y156599D01*
G01X233445Y158155D02*
X235001Y156599D01*
G01X233445Y155005D02*
X235001Y153449D01*
G01X231851Y156599D02*
X230295Y158155D01*
G01Y164454D02*
X231851Y162898D01*
G01X230295Y161304D02*
X231851Y159748D01*
G01X233445Y164454D02*
X235001Y162898D01*
G01X233445Y161304D02*
X235001Y159748D01*
G01X236594Y161304D02*
X238150Y159748D01*
G01X239744Y161304D02*
X241300Y159748D01*
G01X236594Y227446D02*
X235038Y225890D01*
G01X230295Y224296D02*
X228739Y225852D01*
G01X238150Y222703D02*
X236594Y221147D01*
G01X233445D02*
X231889Y219591D01*
G01X233445Y224296D02*
X231889Y222740D01*
G01X236594Y224296D02*
X235038Y222740D01*
G01X233445Y227446D02*
X231889Y225890D01*
G01X230295Y221147D02*
X228739Y222703D01*
G01X230295Y217997D02*
X228739Y216441D01*
G01X241100Y245510D02*
X239613D01*
X233445Y239342D01*
Y233745D01*
G01X230295Y227446D02*
X231851Y229002D01*
G01X227146Y227446D02*
X228702Y229002D01*
G01X227146Y230595D02*
X228702Y232151D01*
Y234431D01*
X229608Y235337D01*
Y241048D01*
X232365Y243805D01*
Y245323D01*
X230400Y247288D01*
Y249600D01*
G01X244150Y250920D02*
Y244181D01*
X242329Y242360D01*
X238827D01*
X235001Y238534D01*
Y232151D01*
X233445Y230595D01*
G01X235326Y245472D02*
Y243715D01*
X231580Y239969D01*
Y235030D01*
X230295Y233745D01*
G01X236594Y230595D02*
X235038Y229039D01*
G01X254355Y300577D02*
X258078Y304300D01*
X268817D01*
X274264Y298853D01*
Y285830D01*
X279663Y280431D01*
Y279723D01*
X276800Y276860D01*
Y262600D01*
X265400Y251200D01*
Y248800D01*
X257450Y240850D01*
X239869D01*
X236594Y237575D01*
Y233745D01*
G01X239100Y250625D02*
X240064D01*
X242332Y248357D01*
Y246742D01*
X241100Y245510D01*
G01X239100Y253775D02*
X240200Y254875D01*
Y259700D01*
X240956Y260456D01*
Y260769D01*
X240961Y260774D01*
Y267089D01*
X239298Y268752D01*
Y268800D01*
G01X230400Y249600D02*
Y252601D01*
X232775Y254976D01*
Y258200D01*
G01X235326Y245472D02*
X235100Y245698D01*
Y250625D01*
G01X235000Y263591D02*
Y253875D01*
X235100Y253775D01*
G01X235000Y263591D02*
X235006D01*
G01X242087Y271427D02*
X238128D01*
X235263Y268562D01*
Y265559D01*
X235000Y265296D01*
Y263591D01*
G01X233225Y319400D02*
X228300D01*
G01X243579Y319310D02*
Y320222D01*
X242601Y321200D01*
X241000D01*
X237900Y324300D01*
G01D02*
X236375Y322775D01*
Y319400D01*
G01X228500Y335075D02*
Y334899D01*
X230899Y332500D01*
X235925D01*
X238500Y335075D01*
G01X237500Y343000D02*
Y348500D01*
X236290Y349710D01*
X230635D01*
X230218Y349293D01*
X230001D01*
X228583Y347875D01*
X228500D01*
G01X242500Y343575D02*
X241925Y343000D01*
X237500D01*
G01X241436Y445784D02*
X248470Y438750D01*
Y431938D01*
X249395Y429705D01*
X250200Y428900D01*
Y418560D01*
X245625Y413985D01*
X233266Y408864D01*
Y405604D01*
X235370Y403500D01*
G01X261900Y423625D02*
Y419048D01*
X260381Y415381D01*
X252285Y407285D01*
X241231D01*
G01X231400Y449500D02*
X232600D01*
X233250Y450150D01*
Y453923D01*
X235689Y459812D01*
Y465590D01*
G01X240010Y456000D02*
Y460221D01*
X240413Y460624D01*
Y465590D01*
G01X240210Y453400D02*
X238511D01*
X238051Y453860D01*
Y465590D01*
G01X231400Y452000D02*
Y454927D01*
X233327Y459580D01*
Y465590D01*
G01X253240Y46559D02*
X251918D01*
X249794Y44435D01*
Y39186D01*
X247717Y37109D01*
Y24764D01*
G01X249475Y55812D02*
Y54012D01*
X242377Y46914D01*
Y44557D01*
X242934Y44000D01*
X245760D01*
G01X264913Y59500D02*
X257500D01*
X256000Y58000D01*
Y56000D01*
G01X254087Y69500D02*
X248000D01*
X247500Y70000D01*
Y72500D01*
X248000Y73000D01*
X250000D01*
G01X269800Y102325D02*
Y100460D01*
X265750Y96410D01*
X260720D01*
X260290Y96840D01*
X249740D01*
X248310Y95410D01*
Y89910D01*
X250920Y87300D01*
X256900D01*
G01X251900Y100100D02*
X253100D01*
X254225Y98975D01*
Y98600D01*
G01Y95100D02*
X252500D01*
X251200Y93800D01*
G01X246000Y123075D02*
X245909Y122984D01*
X242291D01*
X242200Y123075D01*
G01X242195Y137944D02*
Y141003D01*
G01X249193Y164454D02*
X247637Y162898D01*
G01X246043Y167603D02*
X247599Y166047D01*
G01X249193Y170753D02*
X250749Y169197D01*
G01X252342Y170753D02*
X253898Y169197D01*
G01X255492Y173903D02*
X257048Y172347D01*
G01X249193Y183351D02*
X250749Y181795D01*
G01X242894Y183351D02*
X244450Y181795D01*
G01X293907Y168140D02*
X293088D01*
G03X292632Y167951I0J-645D01*
G01X291422Y166741D01*
G02X291005Y166568I-417J416D01*
G01X284929D01*
G03X284448Y166087I0J-481D01*
G01Y162210D01*
G02X283030Y160792I-1418J0D01*
G01X267650D01*
G03X267200Y160342I0J-450D01*
G01Y158865D01*
G03X267650Y158415I450J0D01*
G01X285916D01*
G02X286366Y157965I0J-450D01*
G01Y156490D01*
G02X285916Y156040I-450J0D01*
G01X261077D01*
G02X258762Y158355I0J2315D01*
G01Y167097D01*
G03X258489Y167756I-932J0D01*
G01X255492Y170753D01*
G01X249193Y177052D02*
X250749Y175496D01*
G01X249193Y180202D02*
X250749Y178646D01*
G01X275528Y163811D02*
X271387D01*
G03X270948Y163462I-1J-450D01*
G02X270509Y163113I-439J102D01*
G01X265301D01*
G03X264546Y162358I0J-755D01*
G01Y159018D01*
G02X263794Y158266I-752J0D01*
G01X261605D01*
G02X260850Y159021I0J755D01*
G01Y167398D01*
G03X260550Y168122I-1024J0D01*
G01X259404Y169268D01*
G02X258691Y170987I1717J1719D01*
G01Y172295D01*
G03X257590Y174953I-3759J0D01*
G01X255492Y177051D01*
Y177052D01*
G01X246043Y173903D02*
X247599Y172347D01*
G01X242894Y177052D02*
X244450Y175496D01*
G01X249193Y173903D02*
X250749Y172347D01*
G01X246043Y180202D02*
X247599Y178646D01*
G01X252342Y177052D02*
X253898Y175496D01*
G01X271209Y177524D02*
Y175881D01*
G02X269655Y174327I-1554J0D01*
G01X265038D01*
G03X263855Y173144I0J-1183D01*
G01Y173054D01*
G03X265038Y171871I1183J0D01*
G01X274941D01*
G02X275488Y171628I1J-734D01*
G01X275489Y171627D01*
G02X275699Y171080I-607J-547D01*
G01Y169826D01*
G02X274994Y169121I-705J0D01*
G01X274596D01*
G03X273401Y167926I0J-1195D01*
G01Y167009D01*
G02X270987I-1207J0D01*
G01Y168110D01*
G03X269976Y169121I-1011J0D01*
G01X268476D01*
G03X267986Y168631I0J-490D01*
G01Y167856D01*
G02X265426I-1280J0D01*
G01Y168533D01*
G03X264838Y169121I-588J0D01*
G01X263953D01*
G02X261416Y171658I0J2537D01*
G01Y173291D01*
G03X260756Y174884I-2252J0D01*
G01X260320Y175320D01*
G02Y177074I877J877D01*
G01X260407Y177161D01*
G03Y178867I-853J853D01*
G01X260314Y178960D01*
G03X258670I-822J-822D01*
G01X258607Y178897D01*
G02X256963I-822J822D01*
G01X255776Y180084D01*
G03X255492Y180202I-284J-283D01*
G01X242894D02*
X244450Y178646D01*
G01X242894Y173903D02*
X244450Y172347D01*
G01X242894Y170753D02*
X244450Y169197D01*
G01X242894Y195950D02*
X244450Y197506D01*
G01X246043Y192800D02*
X247599Y191244D01*
G01X255492Y195950D02*
X257048Y197506D01*
G01X252342Y195950D02*
X253898Y197506D01*
G01X249193Y195950D02*
X250749Y197506D01*
G01X246043Y186501D02*
X247599Y184945D01*
G01X267204Y185566D02*
X267197Y185573D01*
X264662D01*
G02X264347Y185661I0J608D01*
G01X264309Y185684D01*
G03X263957Y185783I-352J-576D01*
G01X256463D01*
G02X256058Y185951I0J573D01*
G01X255508Y186501D01*
X255492D01*
G01X242894Y189651D02*
X244450Y188095D01*
G01X264118D02*
X264119Y188096D01*
X265354D01*
G03X265754Y188496I0J400D01*
G01Y190000D01*
G03X265296Y190458I-458J0D01*
G01X262767D01*
G03X262136Y190197I0J-894D01*
G01X260315Y188376D01*
G02X259637Y188095I-678J677D01*
G01X254064D01*
G02X253780Y188213I0J401D01*
G01X252342Y189651D01*
G01X274835Y189927D02*
X274828Y189934D01*
G03X268264Y192654I-6564J-6561D01*
G01X267626D01*
G03X267440Y192700I-186J-353D01*
G01X261003D01*
G03X260520Y192500I0J-683D01*
G01X257860Y189840D01*
G02X257404Y189651I-456J456D01*
G01X255492D01*
G01Y192800D02*
X257048Y191244D01*
G01X249193Y189651D02*
X250749Y188095D01*
G01X242894Y186501D02*
X244450Y184945D01*
G01X249193Y192800D02*
X250749Y191244D01*
G01X249193Y186501D02*
X250749Y184945D01*
G01X249193Y202249D02*
X250749Y203805D01*
G01X255492Y211698D02*
X257048Y213254D01*
G01X249193Y211698D02*
X250749Y213254D01*
G01X246043Y211698D02*
X247599Y213254D01*
G01X246043Y205399D02*
X247599Y206955D01*
G01X246043Y208548D02*
X247599Y210104D01*
G01X249193Y205399D02*
X250749Y206955D01*
G01X246043Y199099D02*
X247599Y200655D01*
G01X255492Y205399D02*
X257048Y206955D01*
G01X249193Y199099D02*
X250749Y200655D01*
G01X255492Y199099D02*
X257048Y200655D01*
G01X252342Y211698D02*
X253898Y213254D01*
G01X249193Y208548D02*
X250749Y210104D01*
G01X242894Y199099D02*
X244450Y200655D01*
G01X252342Y233745D02*
X253898Y235301D01*
G01X248900Y304900D02*
X249600Y305600D01*
X269237D01*
X270369Y305131D01*
X276104Y299396D01*
Y286430D01*
X281081Y281453D01*
Y277681D01*
X278100Y274700D01*
Y261800D01*
X267300Y251000D01*
Y248200D01*
X258550Y239450D01*
X251150D01*
X249300Y237600D01*
G01X250505Y250078D02*
X248828Y248401D01*
X247689Y247929D01*
G01X250023Y257365D02*
Y255237D01*
X250505Y254755D01*
Y253228D01*
G01X242940Y258391D02*
X244108D01*
X245200Y257299D01*
Y254099D01*
X244150Y253049D01*
Y250920D01*
G01X256128Y250104D02*
X253306D01*
X252639Y249437D01*
Y247885D01*
G01X258475Y254872D02*
X258347Y255000D01*
X256716D01*
X256128Y254412D01*
Y253254D01*
G01X242940Y268500D02*
Y261541D01*
G01X253100Y257800D02*
X251679D01*
X251244Y257365D01*
X250023D01*
G01X258325Y259900D02*
X255800D01*
X255700Y260000D01*
G01X252400Y280485D02*
X253818Y281903D01*
X255003D01*
X258000Y284900D01*
G01X252400Y277335D02*
X253100D01*
X253192Y277427D01*
X254872D01*
X257145Y279700D01*
G01X243579Y313514D02*
X243593Y313500D01*
G01D02*
X247425D01*
G01X242700Y306800D02*
X243593Y307693D01*
Y313500D01*
G01X247425Y322000D02*
X246269D01*
X243579Y319310D01*
G01X255165Y367543D02*
X258883D01*
X260800Y365626D01*
Y363200D01*
X264160Y359840D01*
X268170D01*
G01X255165Y375417D02*
X259879D01*
X260600Y376138D01*
Y378709D01*
X261321Y379430D01*
X262339D01*
X263060Y378709D01*
Y376877D01*
X263657Y376280D01*
X272581D01*
G01X255165Y371481D02*
X260781D01*
X262700Y373400D01*
X268200D01*
G01Y390100D02*
X257455Y379355D01*
X255165D01*
G01X260300Y403370D02*
Y386461D01*
X257131Y383292D01*
X255165D01*
G01X252350Y412850D02*
X255950D01*
X257900Y414800D01*
Y416700D01*
G01X256400Y431500D02*
X255200Y434398D01*
X254558Y436515D01*
X249862Y460123D01*
Y465590D01*
G01X256400Y431500D02*
X261125Y426775D01*
X261900D01*
G01X250800Y432500D02*
Y439824D01*
X248600Y442024D01*
Y456500D01*
X247500Y457600D01*
Y465590D01*
G01X250800Y432500D02*
X254010Y429290D01*
Y426789D01*
G01D02*
X254024Y426775D01*
X257900D01*
G01X245138Y465590D02*
Y457066D01*
X244700Y456628D01*
Y450300D01*
X246500Y448500D01*
G01X242776Y465590D02*
Y450724D01*
X243375Y450125D01*
Y448375D01*
G01X267939Y41122D02*
X269258Y42441D01*
X271500D01*
G01X264500Y45000D02*
X268000D01*
X268500Y45500D01*
G01X257800Y82800D02*
X267300D01*
X270100Y85600D01*
X282700D01*
X285590Y88490D01*
X311310D01*
X311770Y88030D01*
Y78330D01*
X314700Y75400D01*
Y74200D01*
X315841Y73059D01*
X317580D01*
G01X259894Y90072D02*
X257375Y92591D01*
Y95100D01*
G01X265801Y106040D02*
X269235D01*
X269800Y105475D01*
G01X257375Y98600D02*
X260970D01*
G01X265900Y109925D02*
X268425Y107400D01*
X271600D01*
X272300Y106700D01*
Y103170D01*
X272760Y102710D01*
X275386D01*
G01X292260Y169643D02*
X292227Y169676D01*
X282470D01*
G02X281399Y170747I0J1071D01*
G01Y176102D01*
G03X281274Y176614I-1103J2D01*
G03X279248Y177933I-2189J-1147D01*
G01X273535D01*
G02X273216Y178065I0J451D01*
G01X268880Y182401D01*
G02Y183152I375J375D01*
G01X269858Y184130D01*
G02X270494I318J-318D01*
G01X274172Y180452D01*
G03X274907I368J367D01*
G01X275902Y181447D01*
G03Y182098I-325J326D01*
G01X272068Y185932D01*
G02Y186666I367J367D01*
G01X272992Y187590D01*
G02X273810I409J-409D01*
G01X282464Y178936D01*
G03X283128I332J332D01*
G01X284159Y179967D01*
G03Y180603I-318J318D01*
G01X282824Y181938D01*
G02Y182505I284J283D01*
G01X284421Y184102D01*
G03Y184668I-283J283D01*
G01X283220Y185869D01*
G03X282653Y185870I-284J-283D01*
G01X281116Y184334D01*
G02X280466I-325J326D01*
G01X274873Y189927D01*
X274835D01*
G01X270472Y188488D02*
X269745Y187383D01*
G02X268089Y185967I-3274J2152D01*
G01X267204Y185566D01*
G01X261300Y250225D02*
X258675Y247600D01*
X258628D01*
G01X273250Y272425D02*
Y270550D01*
X271800Y269100D01*
X268200D01*
X267800Y268700D01*
X266600D01*
G01X261475Y259900D02*
X262700Y261125D01*
Y265100D01*
G01X269400Y281425D02*
Y279425D01*
X273250Y275575D01*
G01X269400Y281425D02*
X267375D01*
X266200Y282600D01*
Y294800D01*
G01X266886Y364610D02*
Y361124D01*
X268170Y359840D01*
G01X276145Y366455D02*
X275120Y365430D01*
X270856D01*
X270036Y364610D01*
G01X266886Y368610D02*
X268200Y369924D01*
Y373400D01*
G01X276400Y370400D02*
X274610Y368610D01*
X270036D01*
G01X266886Y385343D02*
X268200Y386657D01*
Y390100D01*
G01X272581Y376280D02*
X269861Y379000D01*
X268101D01*
X266886Y380215D01*
Y381075D01*
G01X270036D02*
X271176D01*
X271601Y381500D01*
X273100D01*
G01X274880Y387292D02*
X272931Y385343D01*
X270036D01*
G01X271900Y423725D02*
X277600Y418025D01*
Y415900D01*
X281262Y412238D01*
X289950D01*
X290700Y411488D01*
Y410428D01*
X289950Y409678D01*
X281210D01*
X280460Y408928D01*
Y407868D01*
X281210Y407118D01*
X289950D01*
X290700Y406368D01*
Y405308D01*
X289950Y404558D01*
X281210D01*
X280460Y403808D01*
Y399461D01*
X275399Y394400D01*
X271600D01*
X270570Y393370D01*
Y391602D01*
X274880Y387292D01*
G01X260300Y403370D02*
X262730Y405800D01*
X265700D01*
X269925Y401575D01*
Y399500D01*
G01X267000Y419975D02*
X269076D01*
X269900Y420799D01*
Y425999D01*
X269024Y426875D01*
X268000D01*
G01X271500Y418300D02*
X270025Y416825D01*
X267000D01*
G01X257900Y416700D02*
Y423625D01*
G01X271900Y426875D02*
X270000Y428775D01*
Y431600D01*
G01X271890Y465590D02*
Y461968D01*
X273000Y460858D01*
Y457714D01*
X277000Y453714D01*
Y444000D01*
X270000Y437000D01*
Y431600D01*
G01X268000Y426875D02*
X264624D01*
X261400Y430099D01*
Y433100D01*
G01D02*
X263700Y435400D01*
Y436000D01*
X265130Y437430D01*
Y440070D01*
G01X261100Y443500D02*
X267165Y449565D01*
Y466378D01*
G01X269561Y456044D02*
X271474Y457957D01*
Y460071D01*
X269528Y462017D01*
Y466378D01*
G01X286000Y44575D02*
Y47000D01*
G01X281500Y44575D02*
Y47500D01*
X283499Y49499D01*
X288000D01*
X289225Y50724D01*
Y52872D01*
X290000Y53647D01*
Y62425D01*
G01X286000Y41425D02*
X281500D01*
G01X290245Y41428D02*
X290242Y41425D01*
X286000D01*
G01X281500D02*
X279259Y43666D01*
Y49283D01*
X279934Y49958D01*
Y51688D01*
G01X290000Y62425D02*
X286000D01*
G01Y54500D02*
X280625D01*
X280125Y55000D01*
Y55200D01*
G01X286000Y62425D02*
X284925Y63500D01*
X279755D01*
X277675Y61420D01*
Y57650D01*
X280125Y55200D01*
G01X280293Y60430D02*
X280656Y60067D01*
X281433D01*
X284441Y57059D01*
X286000D01*
G01X273645Y99350D02*
X273400Y99105D01*
Y92800D01*
G01X276400Y92300D02*
Y98955D01*
X276795Y99350D01*
G01X284285Y93260D02*
X282175Y91150D01*
X280730D01*
X280270Y90690D01*
Y88470D01*
G01X277000Y79075D02*
X272580Y83495D01*
X272555D01*
X272505Y83545D01*
G01X281000Y79075D02*
Y80050D01*
X277505Y83545D01*
G01X285000Y79075D02*
Y81200D01*
X282705Y83495D01*
X282555D01*
X282505Y83545D01*
G01X281135Y93260D02*
X279376Y95019D01*
X278300D01*
G01X291720Y95610D02*
X288390D01*
X285030Y98970D01*
X283500D01*
X280910Y101560D01*
Y102880D01*
G01X277300Y105825D02*
Y101850D01*
X278960Y100190D01*
Y98910D01*
X282160Y95710D01*
X284524D01*
X289894Y90340D01*
X313450D01*
X317444Y94334D01*
X318512Y96912D01*
X319870Y98270D01*
X321200D01*
X325440Y102510D01*
X341860D01*
X345195Y105845D01*
G01X281300Y108325D02*
X279835D01*
X279060Y107550D01*
Y101640D01*
X280020Y100680D01*
Y99350D01*
X282600Y96770D01*
X285450D01*
X290820Y91400D01*
X313010D01*
X315080Y93470D01*
Y95980D01*
G01X281250Y115925D02*
X283925D01*
X285250Y117250D01*
G01X273644Y174267D02*
Y175456D01*
G02X274246Y176058I602J0D01*
G01X275765D01*
G02X276367Y175456I0J-602D01*
G01Y174946D01*
G03X277064Y174249I697J0D01*
G02X277600Y173713I0J-536D01*
G01Y167549D01*
G03X277697Y167099I1081J-3D01*
G03X277806Y166895I1841J852D01*
G01Y166894D01*
G03X278440Y166537I634J385D01*
G01X281646D01*
G02X282096Y166087I0J-450D01*
G01Y164261D01*
G02X281646Y163811I-450J0D01*
G01X275528D01*
G01X282975Y172975D02*
X283497Y172453D01*
G03X283884Y172157I1308J1309D01*
G03X285945Y171338I3881J6765D01*
G03X286362Y171289I416J1739D01*
G01X287608D01*
G01X289254Y191690D02*
X289225Y191719D01*
X285219D01*
G02X284817Y191843I-2J708D01*
G02X284439Y192563I495J719D01*
G01Y198611D01*
G03X283989Y199061I-450J0D01*
G01X281904D01*
G03X281454Y198611I0J-450D01*
G01Y196056D01*
G02X281004Y195606I-450J0D01*
G01X277123D01*
G03X276446Y194929I0J-677D01*
G01Y193935D01*
G03X277225Y193156I779J0D01*
G01X281004D01*
G02X281454Y192706I0J-450D01*
G01Y189010D01*
G03X281907Y188557I453J0D01*
G01X288768D01*
G03X289381Y188811I0J867D01*
G01X290757Y190187D01*
G01X292404Y213737D02*
Y214948D01*
G03X292147Y215537I-800J2D01*
G03X291726Y215700I-419J-456D01*
G01X283964D01*
G02X283147Y216517I0J817D01*
G01Y222547D01*
G02X283597Y222997I450J0D01*
G01X297565D01*
G02X298015Y222547I0J-450D01*
G01Y220997D01*
G02X297565Y220547I-450J0D01*
G01X286024D01*
G03X285574Y220097I0J-450D01*
G01Y218547D01*
G03X286024Y218097I450J0D01*
G01X293406D01*
G02X294580Y216923I0J-1174D01*
G01Y213113D01*
X294434Y212761D01*
X293907Y212234D01*
G01X299138Y244513D02*
X295454Y248197D01*
Y275821D01*
X288241Y283034D01*
X282889D01*
X279307Y286616D01*
Y344227D01*
X280741Y345661D01*
Y353255D01*
X279307Y354689D01*
Y388511D01*
X287476Y396680D01*
G01X281300Y308800D02*
Y341400D01*
X288200Y348300D01*
G01D02*
Y355800D01*
X284475Y359525D01*
Y371933D01*
G01D02*
X284566Y372024D01*
X286189D01*
X286782Y372617D01*
X288342D01*
X288425Y372700D01*
G01X285191Y390840D02*
Y389150D01*
X286841Y387500D01*
X289686D01*
G01X333075Y385500D02*
X332790D01*
X323990Y394300D01*
X320913D01*
X315744Y399469D01*
X282429D01*
X275360Y392400D01*
X272400D01*
G01X284100Y419875D02*
X285730Y421505D01*
Y423859D01*
X285500Y424089D01*
Y426100D01*
G01X281300Y416200D02*
X283575D01*
X284100Y416725D01*
G01X276400Y431810D02*
Y435500D01*
X279700Y438800D01*
Y454200D01*
X275020Y458880D01*
Y460650D01*
X274252Y461418D01*
Y465590D01*
G01X285500Y426100D02*
Y428100D01*
X287200Y429800D01*
Y438000D01*
X293796Y444596D01*
Y461423D01*
X293150Y462069D01*
Y466378D01*
G01X275100Y427682D02*
X276382Y426400D01*
X278400D01*
G01D02*
Y426848D01*
X281700Y430148D01*
Y456200D01*
X280300Y457600D01*
Y460732D01*
X278976Y462056D01*
Y466378D01*
G01X284200Y432900D02*
Y440200D01*
X285800Y441800D01*
Y454200D01*
X281700Y458300D01*
Y461301D01*
X281339Y461662D01*
Y466378D01*
G01X274619Y424725D02*
X275275D01*
X275930Y424070D01*
X280740D01*
X281200Y424530D01*
Y427700D01*
X284200Y430700D01*
Y432900D01*
G01X291623Y447747D02*
X290301D01*
X287224Y450824D01*
Y459091D01*
X286063Y460252D01*
Y466378D01*
G01X295402Y41878D02*
X289024Y35500D01*
X288144D01*
X286811Y34167D01*
Y29095D01*
G01X290245Y41428D02*
X290695Y41878D01*
X295402D01*
G01X297466Y51521D02*
X297046Y51941D01*
X293000D01*
G01X297575Y79500D02*
Y73738D01*
G01X293773Y73530D02*
X295678Y71625D01*
X303547D01*
X306075Y74153D01*
Y79500D01*
G01X302091Y74553D02*
X300618Y76026D01*
Y81294D01*
X303130Y83806D01*
Y84000D01*
G01X293630D02*
Y82630D01*
X289736Y78736D01*
Y78607D01*
G01D02*
X289843Y78500D01*
X291794D01*
X292794Y79500D01*
X294425D01*
G01X336500Y303375D02*
X342935D01*
X348987Y297323D01*
Y226197D01*
X344160Y221370D01*
X315680D01*
X314390Y220080D01*
Y217680D01*
X315590Y216480D01*
X318170D01*
X319030Y217340D01*
X343987D01*
X347927Y213400D01*
Y114007D01*
X344650Y110730D01*
X329570D01*
X326520Y107680D01*
X322200D01*
X318620Y104100D01*
Y100660D01*
X317940Y99980D01*
X312160D01*
X311300Y99120D01*
X298690D01*
X295180Y95610D01*
X291720D01*
G01X301936Y149447D02*
X301544Y149839D01*
G02X295400Y163428I14935J14936D01*
G01Y165984D01*
G03X294931Y167116I-1600J0D01*
G01X293907Y168140D01*
G01X309936Y149447D02*
X302531Y156852D01*
G02X299807Y163429I6578J6577D01*
G01Y167700D01*
G03X296987Y174508I-9628J0D01*
G01X293907Y177588D01*
G01X289110Y163487D02*
X288417Y162794D01*
G03X288249Y162389I405J-405D01*
G01Y156199D01*
G03X288699Y155749I450J0D01*
G01X290174D01*
G03X290700Y156275I0J526D01*
G01Y164933D01*
X290757Y164990D01*
G01X305936Y149447D02*
X301882Y153501D01*
G02X297730Y163525I10024J10024D01*
G01Y168235D01*
G03X296037Y172322I-5780J0D01*
G01X296024D01*
X295410Y172936D01*
G01X292260Y163487D02*
X293661Y164888D01*
X293907Y164990D01*
G01Y171289D02*
X295410Y169786D01*
G01X292404Y176085D02*
X293907Y177588D01*
G01X295410Y172936D02*
X293907Y174439D01*
G01X290757Y171289D02*
X289254Y172792D01*
G01X290757Y168140D02*
X292260Y169643D01*
G01X295410Y179235D02*
X293907Y180738D01*
G01X290757Y174439D02*
X292384Y172936D01*
G01X290757Y177588D02*
X289254Y176085D01*
G01X295411Y185534D02*
X296105Y184840D01*
G02X296793Y183810I-2245J-2245D01*
G01X301205Y173161D01*
G02X301463Y171864I-3131J-1297D01*
G01Y162852D01*
G03X302123Y161260I2252J1D01*
G01X313936Y149447D01*
G01X290757Y180738D02*
X292260Y179235D01*
G01X290757Y193336D02*
X289254Y194839D01*
G01X292404Y191690D02*
Y189077D01*
G03X292978Y188503I574J0D01*
G01X298892D01*
G03X299342Y188953I0J450D01*
G01Y192864D01*
G03X298892Y193314I-450J0D01*
G01X295943D01*
G03X295444Y192815I0J-499D01*
G01Y190768D01*
G02X294863Y190187I-581J0D01*
G01X293907D01*
G01Y187037D02*
X292404Y185534D01*
G01X289254Y182385D02*
X291994D01*
G03X292394Y182785I0J400D01*
G01Y183488D01*
G03X291994Y183888I-400J0D01*
G01X290757D01*
G01X295411Y185534D02*
X295410D01*
X293907Y183888D01*
G01Y205935D02*
X294757D01*
G03X295517Y206695I0J760D01*
G01Y207181D01*
G02X296674Y208338I1157J0D01*
G01X298868D01*
G03X301118Y210588I0J2250D01*
G01Y216448D01*
G03X299961Y217605I-1157J0D01*
G01X299871D01*
G03X298714Y216448I0J-1157D01*
G01Y213624D01*
G02X297902Y212812I-812J0D01*
G01X297812D01*
G03X297000Y212000I0J-812D01*
G01Y210923D01*
G03X297450Y210473I450J0D01*
G01X298714D01*
Y210477D01*
G01X308008Y207438D02*
X302266D01*
G03X301834Y207310I-1J-789D01*
G03X301047Y206302I1081J-1656D01*
G03X300978Y205886I1198J-412D01*
G01Y204872D01*
G03X302208Y203816I1068J0D01*
G01X302305Y203801D01*
G03X303418Y204757I146J956D01*
G01Y204845D01*
G02X304545Y205972I1127J0D01*
G01X306468D01*
X306505Y205935D01*
G01X292404Y210587D02*
X292260Y210443D01*
Y207438D01*
X290757Y205935D01*
G01X293907Y202785D02*
X292404Y201282D01*
G01X306505Y196486D02*
X305447D01*
G02X303855Y197146I1J2252D01*
G01X299667Y201334D01*
G01X290757Y199636D02*
X289254Y201139D01*
G01X299000Y291425D02*
X295000Y287425D01*
Y285500D01*
X296600Y283900D01*
X298100D01*
G01X307087Y291639D02*
X305148Y289700D01*
X302700D01*
X300000Y287000D01*
Y285800D01*
X298100Y283900D01*
G01X305306Y277100D02*
X304906Y277500D01*
X300980D01*
X298840Y279640D01*
G01X288000Y290925D02*
X292000D01*
G01X287755Y287538D02*
Y290680D01*
X288000Y290925D01*
G01X297760Y320382D02*
Y311835D01*
X297425Y311500D01*
G01D02*
Y307000D01*
G01X303512Y369512D02*
X299212D01*
X297208Y367508D01*
X293300D01*
G01D02*
Y368020D01*
X296780Y371500D01*
G01X290501Y377400D02*
X293600D01*
X297551Y373449D01*
X303512D01*
G01X291575Y372700D02*
X290501Y373774D01*
Y377400D01*
G01X290450Y382690D02*
X292836Y385076D01*
Y387500D01*
G01X303512Y377386D02*
X299514D01*
X294210Y382690D01*
X290450D01*
G01X292836Y391600D02*
X294201D01*
X299125Y386676D01*
X303343Y384930D01*
X316171D01*
X320126Y383292D01*
G01X287630Y389378D02*
Y389544D01*
X289686Y391600D01*
G01X291703Y450819D02*
X290397D01*
X288819Y452397D01*
Y460049D01*
X288425Y460443D01*
Y466378D01*
G01X302091Y74553D02*
Y78666D01*
X302925Y79500D01*
G01X320500Y100400D02*
X316080Y95980D01*
X315080D01*
G01X307400Y122300D02*
Y120100D01*
X308600Y118900D01*
X311701D01*
X315776Y122975D01*
X316700D01*
G01X309936Y141447D02*
X310150D01*
X311885Y143182D01*
Y147216D01*
X309936Y149165D01*
Y149447D01*
G01X301936Y141347D02*
X302100D01*
X303885Y143132D01*
Y147214D01*
X301936Y149163D01*
Y149447D01*
G01X305936Y141447D02*
X306150D01*
X307885Y143182D01*
Y147250D01*
X305936Y149199D01*
Y149447D01*
G01X313936Y141447D02*
X314150D01*
X315225Y142522D01*
G03X315885Y144114I-1592J1593D01*
G01Y146274D01*
G03X315220Y147879I-2271J-1D01*
G01X313936Y149163D01*
Y149447D01*
G01X327383Y164347D02*
X326015D01*
G03X324999Y163926I0J-1436D01*
G01X324936Y163863D01*
G02X323920Y163442I-1016J1015D01*
G01X321970D01*
G03X320378Y162782I1J-2252D01*
G01X320195Y162599D01*
G02X318603Y161939I-1593J1592D01*
G01X313789D01*
G02X311940Y162705I0J2615D01*
G01X311158Y163487D01*
G01D02*
X309655Y164990D01*
G01X331405Y159911D02*
X325976D01*
X325373Y159308D01*
X313689D01*
G02X306304Y162367I0J10444D01*
G01X305352Y163319D01*
G02X305002Y164163I843J844D01*
G01Y169786D01*
G01X308008Y166637D02*
X306505Y168140D01*
G01X331405Y169911D02*
X330259D01*
X329695Y169347D01*
X327383D01*
X325498Y167462D01*
X319571D01*
X318686Y166577D01*
X308068D01*
X308008Y166637D01*
G01X331405Y154911D02*
X328463D01*
X327878Y155496D01*
X315447D01*
G02X307050Y158974I0J11876D01*
G01X303422Y162602D01*
G02X303304Y162886I283J284D01*
G01Y177094D01*
G02X303617Y177850I1069J0D01*
G01X305002Y179235D01*
G01X312804Y171289D02*
X314930D01*
G01X312804Y177588D02*
X314930D01*
G01X306505D02*
X305002Y176085D01*
G01Y169786D02*
X306505Y171289D01*
G01Y174439D02*
X305002Y172936D01*
G01X309655Y171289D02*
X308152Y169786D01*
G01X331405Y179911D02*
X329457D01*
X324949Y175403D01*
X319490D01*
X316950Y172863D01*
X312307D01*
G03X310467Y172101I0J-2603D01*
G01X309655Y171289D01*
G01X327830Y174403D02*
X324846Y171419D01*
X320924D01*
X319191Y169686D01*
X311335D01*
X311158Y169643D01*
G01D02*
X309655Y168140D01*
G01Y174439D02*
X308152Y172936D01*
G01X324777Y182042D02*
X322120D01*
X316093Y176015D01*
X312951D01*
G03X310014Y174798I1J-4154D01*
G01X309655Y174439D01*
G01X308152Y176085D02*
X309655Y177588D01*
G01X328265Y187045D02*
X326082Y184862D01*
X321795D01*
X316551Y179618D01*
G02X315419Y179149I-1132J1132D01*
G01X312112D01*
G03X310582Y178515I0J-2163D01*
G01X309655Y177588D01*
G01X305002Y179235D02*
X306505Y180738D01*
G01X309655D02*
X308152Y179235D01*
G01X312804Y174439D02*
X314930D01*
G01X306505Y190187D02*
X308008Y191690D01*
G01X309655Y190187D02*
X311158Y191690D01*
G01X306505Y187037D02*
X308008Y188540D01*
G01X312804Y196486D02*
X314307Y197989D01*
G01X309655Y205935D02*
X308152Y204432D01*
G01X306505Y202785D02*
X305002Y204432D01*
G01X309655Y209084D02*
X311158Y210587D01*
G01X308008Y198133D02*
X305721D01*
G02X304129Y198793I1J2252D01*
G01X303203Y199719D01*
G02Y201803I1042J1042D01*
G01X303265Y201865D01*
G02X305349I1042J-1042D01*
G01X306157Y201057D01*
G02X306505Y200217I-840J-840D01*
G01Y199636D01*
G01X312804D02*
X314307Y201139D01*
G01X311670Y285160D02*
X316118D01*
G01X308456Y285092D02*
X308524Y285160D01*
X311670D01*
G01X308456Y281088D02*
Y285092D01*
G01Y277100D02*
Y281088D01*
G01X302879Y279686D02*
X304281Y281088D01*
X305306D01*
G01X309700Y294789D02*
X307087D01*
G01X303077Y291639D02*
X303937D01*
X305199Y292901D01*
Y294339D01*
X305649Y294789D01*
X307087D01*
G01X312300Y340700D02*
X331700D01*
X336600Y335800D01*
Y312599D01*
X332500Y308499D01*
Y303375D01*
G01X328000Y62100D02*
Y66700D01*
X326759Y67941D01*
X325020D01*
G01Y70500D02*
X328301D01*
X331801Y74000D01*
X334225D01*
G01X321416Y138309D02*
Y141916D01*
X321600Y142100D01*
G01X322000Y144925D02*
X321600Y144525D01*
Y142100D01*
G01X326052Y148439D02*
Y144423D01*
G01X323384Y138309D02*
Y140505D01*
X326052Y143173D01*
Y144423D01*
G01X331405Y164911D02*
X330370D01*
G03X329765Y164660I0J-855D01*
G01X329703Y164598D01*
G02X329098Y164347I-605J604D01*
G01X327383D01*
G01X331405Y174911D02*
X330055D01*
X329547Y174403D01*
X327830D01*
G01X331405Y182926D02*
X329420D01*
X328536Y182042D01*
X324777D01*
G01X331405Y189911D02*
X331131D01*
X328265Y187045D01*
G01X345195Y105845D02*
X348987Y109637D01*
Y215850D01*
X345697Y219140D01*
X317110D01*
G01X327536Y289097D02*
X328397D01*
X331385Y292085D01*
X333749D01*
G01X320126Y363606D02*
X321994D01*
X323600Y362000D01*
X324106D01*
X325500Y360606D01*
X327531D01*
X329925Y363000D01*
G01X320126Y367543D02*
X324000D01*
X325900Y365643D01*
G01X329925Y367500D02*
X328068Y365643D01*
X325900D01*
G01X326100Y375717D02*
X320426D01*
X320126Y375417D01*
G01X329925Y376500D02*
X326883D01*
X326100Y375717D01*
G01X320126Y371481D02*
X325400D01*
X326200Y370681D01*
G01X329925Y372000D02*
X328606Y370681D01*
X326200D01*
G01X320126Y379355D02*
X325006D01*
X326375Y380724D01*
G01X329925Y385500D02*
Y384274D01*
X326375Y380724D01*
G01X341000Y61300D02*
X347500Y54800D01*
Y32600D01*
X342420Y27520D01*
X331693D01*
G01X341000Y61300D02*
X336201D01*
X334225Y63276D01*
Y66000D01*
G01Y74000D02*
Y70000D01*
G01D02*
Y66000D01*
G01X337375D02*
X339900D01*
G01X334250Y164911D02*
X331405D01*
G01X334250Y159911D02*
X331405D01*
G01X334250Y154911D02*
X331405D01*
G01X334250Y179911D02*
X331405D01*
G01X334250Y174911D02*
X331405D01*
G01X334250Y169911D02*
X331405D01*
G01X334250Y183926D02*
X332405D01*
X331405Y182926D01*
G01X334250Y189911D02*
X331405D01*
G01X333749Y292085D02*
X333725Y292109D01*
Y295900D01*
G01X336500Y300225D02*
X332500D01*
G01X333725Y295900D02*
X332500Y297125D01*
Y300225D01*
G01X333075Y358500D02*
Y363000D01*
G01Y358500D02*
X335475D01*
G01Y367500D02*
X333075D01*
G01Y372000D02*
X335700D01*
X335708Y372008D01*
G01X333075Y381000D02*
Y376500D01*
G01X335500Y380000D02*
X334500Y381000D01*
X333075D01*
G54D55*
X34642Y251327D03*
G54D37*
X30148Y246113D03*
X30783Y264500D03*
X28183Y316900D03*
X19883Y328600D03*
X39983Y38000D03*
X45467Y214718D03*
X36783Y214700D03*
X46583Y241000D03*
X47383Y248800D03*
X39475Y246116D03*
X46583Y244900D03*
X37783Y264500D03*
X53699Y38500D03*
X54633Y211200D03*
X51783Y260800D03*
X49983Y328000D03*
Y324000D03*
Y344000D03*
Y348000D03*
Y364000D03*
Y368000D03*
Y372000D03*
Y376000D03*
Y380000D03*
Y384000D03*
X50383Y394350D03*
X66458Y116450D03*
X77502Y135866D03*
X81049Y118216D03*
X94473Y428020D03*
X118083Y102000D03*
Y107600D03*
X110983Y102000D03*
Y107500D03*
X117483Y123500D03*
X121783Y346400D03*
Y342500D03*
X118983Y415000D03*
X130483Y50000D03*
X136983Y201500D03*
X133483Y253700D03*
X132683Y261900D03*
X136083Y429000D03*
X152483Y142000D03*
X143483Y175200D03*
X143493Y179160D03*
X151577Y182594D03*
X139883Y348300D03*
Y351900D03*
X149563Y419250D03*
X166283Y112800D03*
X159388Y153077D03*
X158592Y182644D03*
X158699Y178679D03*
X158683Y174800D03*
X158733Y187354D03*
X158783Y191700D03*
X159483Y224000D03*
X158282Y313560D03*
X158283Y309700D03*
X160983Y350500D03*
X153483Y429000D03*
X174383Y272800D03*
X185983Y88000D03*
Y92000D03*
X189983Y267000D03*
X196983Y264810D03*
X187583Y294500D03*
X192183Y311100D03*
X210623Y244900D03*
X209783Y419600D03*
X217403Y102014D03*
X225103Y258930D03*
X225983Y296600D03*
Y300600D03*
X220883Y416000D03*
X236283Y319400D03*
X257283Y98600D03*
Y95100D03*
X255083Y110300D03*
X269944Y368610D03*
Y381075D03*
X284193Y93260D03*
X276703Y99350D03*
X286041Y138403D03*
X297483Y79500D03*
X291983Y100400D03*
X297743Y142907D03*
X300483Y311500D03*
X293208Y358508D03*
Y363008D03*
X292744Y387500D03*
X305983Y79500D03*
X308364Y273256D03*
X329110Y144423D03*
X324363Y275940D03*
X323142Y294816D03*
X337283Y70000D03*
X337308Y154911D03*
Y164911D03*
Y159911D03*
Y169911D03*
Y179911D03*
Y174911D03*
Y183926D03*
Y189911D03*
X336807Y292085D03*
G54D46*
X28260Y322441D03*
Y325000D03*
Y327559D03*
X35740D03*
Y325000D03*
Y322441D03*
G54D73*
X77384Y240085D03*
X75416D03*
X73447D03*
X77384Y250715D03*
X75416D03*
X73447D03*
X79353Y240085D03*
Y250715D03*
X101253Y239985D03*
X99284D03*
X97316D03*
X95347D03*
X101253Y250615D03*
X99284D03*
X97316D03*
X95347D03*
G54D91*
X137240Y152985D03*
X133500D03*
X129760D03*
X137240Y163615D03*
X133500D03*
X129760D03*
G54D82*
X113760Y74441D03*
Y77000D03*
X121240D03*
Y74441D03*
X113760Y79559D03*
X121240D03*
X132740Y44459D03*
Y41900D03*
Y39341D03*
X125260D03*
Y41900D03*
Y44459D03*
X253240Y46559D03*
Y44000D03*
Y41441D03*
X245760D03*
Y44000D03*
Y46559D03*
G54D28*
X35256Y140183D03*
Y174347D03*
G54D19*
X16608Y190420D03*
X18000Y233084D03*
X42281Y206242D03*
X46307D03*
X40500Y233984D03*
X48440Y255594D03*
X40500Y373984D03*
Y366984D03*
Y380984D03*
Y402484D03*
X48600Y431984D03*
X44700D03*
X52500Y65984D03*
X63918Y126139D03*
X60090Y126144D03*
X61216Y228784D03*
X52440Y255594D03*
X63300Y260784D03*
X49938Y308780D03*
X55800Y330984D03*
X52500Y431984D03*
X56500D03*
X69200Y183784D03*
X65500D03*
X73400Y222684D03*
X77500D03*
X75400Y232884D03*
X65216Y228784D03*
X72500Y261484D03*
X67000Y405984D03*
X71000D03*
X88083Y124956D03*
X81500Y222684D03*
X91500Y272484D03*
X93500Y261984D03*
X86500Y261784D03*
X90804Y333304D03*
X79000Y405984D03*
X102800Y87984D03*
X100000Y95984D03*
X99700Y122084D03*
X95800D03*
X100400Y134984D03*
X96400D03*
X106800Y259584D03*
X99500Y272484D03*
X103500D03*
X95500D03*
X107400Y273384D03*
X103100Y331184D03*
X98000D03*
X98680Y428434D03*
X120500Y41984D03*
X112500D03*
X110800Y260184D03*
X119760Y271185D03*
X115260D03*
X111500Y270984D03*
X114800Y260784D03*
X111100Y279184D03*
X115260Y279185D03*
X119760D03*
X117918Y331472D03*
X113918D03*
X118800Y357184D03*
X129500Y143984D03*
X137525Y143811D03*
X133500Y143984D03*
X133000Y176484D03*
X129000D03*
X126500Y256684D03*
X124500Y264184D03*
X128760Y271185D03*
X124260D03*
X133000Y270984D03*
X124260Y279185D03*
X128760D03*
X129918Y331472D03*
X133918D03*
X141500Y143484D03*
X152434Y153199D03*
X141500Y241484D03*
X145918Y331472D03*
X149918D03*
X139900Y431984D03*
X155300Y104284D03*
X155530Y122104D03*
X164400Y122984D03*
X168000Y137984D03*
X160457Y145493D03*
X156430Y145465D03*
X160500Y205584D03*
X156028Y219703D03*
X157500Y231984D03*
X156973Y252495D03*
X165013D03*
X160713Y260513D03*
X156713D03*
X155000Y292484D03*
X165200Y320484D03*
X161026Y346680D03*
X178000Y107284D03*
X172632Y123010D03*
X168616D03*
X178186Y122710D03*
X180000Y137784D03*
X176000D03*
X178174Y261005D03*
X169026Y346680D03*
X173026D03*
X187272Y81937D03*
X191312D03*
X196065Y123010D03*
X191400D03*
X184000Y137884D03*
X183350Y262264D03*
X188000Y320884D03*
X193750Y363734D03*
Y379484D03*
Y388484D03*
X192334Y432236D03*
X211000Y43984D03*
X200000Y122984D03*
X210189Y123010D03*
X204000Y122984D03*
X199985Y137853D03*
X204120D03*
X207912Y253108D03*
X199810Y253270D03*
X209500Y275984D03*
X199405Y432236D03*
X203400Y432184D03*
X219000Y43984D03*
X214500Y93984D03*
X223300Y122984D03*
X214464Y123010D03*
X218200Y252084D03*
X221800D03*
X222300Y282084D03*
X221260Y313344D03*
X220600Y320984D03*
X226650Y379294D03*
X213500Y379484D03*
X237000Y44484D03*
X233000D03*
X242200Y122984D03*
X228600D03*
X238382Y123010D03*
X233511Y138053D03*
X242195Y137853D03*
X237655D03*
X239100Y253684D03*
X235100D03*
X228500Y334984D03*
Y347784D03*
X246000Y122984D03*
X252400Y280394D03*
X254010Y426698D03*
X265900Y112984D03*
X261300Y253284D03*
X268000Y426784D03*
X286000Y44484D03*
X281500D03*
X286000Y65484D03*
X277000Y78984D03*
X281000D03*
X285000D03*
X285295Y113870D03*
X277300Y108884D03*
X285295Y131451D03*
X277049Y131538D03*
X278028Y140298D03*
X272698Y140308D03*
X284100Y419784D03*
X290245Y44487D03*
X301936Y141256D03*
X288000Y293984D03*
X316066Y113869D03*
X313936Y141356D03*
X309936D03*
X305936D03*
X303077Y294698D03*
X307087D03*
X320872Y120186D03*
X317936Y149356D03*
X322000Y147984D03*
X333278Y148348D03*
X333839Y278881D03*
X333828Y286261D03*
X332500Y303284D03*
X336500D03*
G54D64*
G01X48500Y112559D02*
Y113000D01*
X44800Y116700D01*
X25600D01*
X25200Y116300D01*
G01X43925Y38000D02*
Y39925D01*
X45500Y41500D01*
G01X42011Y58317D02*
X35304D01*
G01X42011D02*
Y57085D01*
X42920Y56176D01*
Y52897D01*
G01X50392Y195712D02*
X46392D01*
G01X46675Y241000D02*
X46475Y240800D01*
Y236809D01*
X47760Y235524D01*
G01X46675Y241000D02*
X47901D01*
X50271Y238630D01*
X50567D01*
G01X50075Y360000D02*
Y356075D01*
X49075Y355075D01*
X47500D01*
G01X40500Y377925D02*
X37875D01*
G01X47325Y397850D02*
X44490D01*
G01X41200Y429100D02*
Y426975D01*
X40800Y426575D01*
G01X58976Y36402D02*
Y37137D01*
X57113Y39000D01*
G01D02*
X62465D01*
X65709Y42244D01*
G01X57113Y39000D02*
X54075D01*
X53791Y38716D01*
Y38500D01*
G01X52876Y195712D02*
X50392D01*
G01X51849Y206333D02*
Y208559D01*
X52050Y208760D01*
G01X50075Y364000D02*
Y360000D01*
G01D02*
X52900D01*
G01X72800Y183875D02*
X75300D01*
G01X81500Y219625D02*
Y217223D01*
X78277Y214000D01*
X75000D01*
G01X72500Y258425D02*
Y258360D01*
G01Y258425D02*
X70436D01*
X69599Y257588D01*
X69578D01*
X68990Y257000D01*
G01X76425Y259200D02*
X75199D01*
X74424Y258425D01*
X72500D01*
G01X66250Y421325D02*
Y423550D01*
X68100Y425400D01*
G01X86700Y119100D02*
X88083Y120483D01*
Y121897D01*
G01X92500Y116200D02*
X92891D01*
X95716Y119025D01*
X95800D01*
G01X92405Y135056D02*
X89256D01*
G01X92405D02*
Y137205D01*
X94733Y139533D01*
X102862Y142900D01*
X121800D01*
X128100Y136600D01*
X131028D01*
X132828Y138400D01*
G01X89925Y255500D02*
Y257350D01*
X90800Y258225D01*
G01X93500Y258925D02*
X91500D01*
X90800Y258225D01*
G01X99700Y119025D02*
Y117160D01*
X100360Y116500D01*
G01X97300Y260875D02*
Y263197D01*
X97177Y263320D01*
G01X120500Y42075D02*
X119000Y43575D01*
Y44600D01*
G01X116500Y42075D02*
X115000Y43575D01*
Y44500D01*
G01X118224Y55240D02*
X121624D01*
X122564Y54300D01*
X126425D01*
G01X121095Y68911D02*
X124184Y72000D01*
X134600D01*
X136669Y69931D01*
X140549Y68324D01*
X151024D01*
X152900Y70200D01*
Y75500D01*
X152800Y75600D01*
G01X120331Y243075D02*
X120606Y242800D01*
X122876D01*
G01X111100Y276125D02*
Y273700D01*
G01X121875Y346400D02*
X122975Y345300D01*
X124400D01*
G01X116500Y406175D02*
X119200D01*
G01X126425Y57000D02*
Y54300D01*
G01X133500Y140925D02*
X132828Y140253D01*
Y138400D01*
G01X129760Y163615D02*
Y172665D01*
X129000Y173425D01*
G01D02*
X127075D01*
X126500Y174000D01*
G01X133575Y253700D02*
Y255525D01*
X133000Y256100D01*
G01X135824Y247740D02*
Y251451D01*
X133575Y253700D01*
G01X148400Y167675D02*
X147795Y167070D01*
X142371D01*
X140554Y168887D01*
G01X155625Y171000D02*
X153210D01*
X153200Y170990D01*
G01X148370Y175325D02*
X148045Y175000D01*
X143775D01*
X143575Y175200D01*
G01X140554Y171688D02*
X141625D01*
X143575Y173638D01*
Y175200D01*
G01X140554Y168887D02*
Y171688D01*
G01X142150Y187150D02*
X143835Y188835D01*
X145296D01*
G01X147501Y187354D02*
X146777D01*
X145296Y188835D01*
G01X143980Y199674D02*
X145102D01*
X147088Y197688D01*
X148995D01*
X150983Y195700D01*
X154225D01*
G01X147900Y351675D02*
X143993D01*
X143945Y351723D01*
G01X143013Y365197D02*
Y361886D01*
X144170Y360729D01*
Y354371D01*
X143945Y354146D01*
G01X171523Y107140D02*
X168060D01*
X166375Y108825D01*
Y112800D01*
G01X155530Y119045D02*
Y116640D01*
G01X169100Y113900D02*
X168000Y112800D01*
X166375D01*
G01X168000Y134925D02*
X166700Y133625D01*
Y132360D01*
G01X155441Y281289D02*
Y288984D01*
X155000Y289425D01*
G01X162160Y313560D02*
X158374D01*
G01X161075Y350500D02*
X161300Y350725D01*
Y354600D01*
G01X182925Y96000D02*
Y96824D01*
X184800Y98699D01*
Y100300D01*
G01X177825Y272800D02*
Y271025D01*
X176900Y270100D01*
G01X177825Y272800D02*
X174475D01*
G01X191400Y119951D02*
X196065D01*
G01X202425Y273000D02*
X195667D01*
X195370Y273297D01*
G01X197012Y296565D02*
X192040D01*
X189975Y294500D01*
X187675D01*
G01D02*
Y297423D01*
X187623Y297475D01*
G01X183325Y300200D02*
X183425Y300100D01*
Y299275D01*
X185225Y297475D01*
X187623D01*
G01X192275Y311100D02*
X192575Y310800D01*
X195999D01*
X196999Y309800D01*
X201970D01*
X203211Y311041D01*
G01X192275Y311100D02*
Y308487D01*
X192448Y308314D01*
G01X188000Y317825D02*
X198322D01*
X198672Y318175D01*
G01D02*
X201997Y321500D01*
X211300D01*
X217675Y327875D01*
X220600D01*
G01X219000Y44075D02*
Y57539D01*
X214306Y62233D01*
G01X222648Y94148D02*
X224052D01*
X236340Y81860D01*
Y76810D01*
X245300Y67850D01*
Y55500D01*
X237000Y47200D01*
G01X217495Y102014D02*
X218209Y101300D01*
X219900D01*
G01X219800Y94300D02*
X219900Y94400D01*
G01D02*
Y101300D01*
G01X228500Y331925D02*
X224475D01*
X222700Y333700D01*
Y340200D01*
X225867Y343367D01*
Y345033D01*
G01X228500Y344725D02*
X226175D01*
X225867Y345033D01*
G01X237000Y44575D02*
Y47200D01*
G01X240429Y313514D02*
Y316504D01*
X240500Y316575D01*
G01X240429Y319310D02*
Y316646D01*
X240500Y316575D01*
G01X271500Y47559D02*
X276984D01*
X277000Y47575D01*
G01D02*
Y51665D01*
G01Y75925D02*
Y73600D01*
X277900Y72700D01*
X279800D01*
G01X300425Y57000D02*
Y54516D01*
G01X297370Y84000D02*
X300070D01*
G01X292000Y294075D02*
X298500D01*
X299000Y294575D01*
G01X306500Y301500D02*
X300500D01*
X299000Y300000D01*
Y294575D01*
G01X306870Y84000D02*
X309570D01*
G01X329925Y356016D02*
Y358500D01*
G01Y381000D02*
Y381725D01*
X331500Y383300D01*
X62458Y346425D03*
Y343275D03*
Y355873D03*
X58564Y354280D03*
X65607Y352724D03*
Y359023D03*
Y371584D03*
X62458Y390481D03*
X75056Y346425D03*
X68757D03*
X81355D03*
X78206Y349574D03*
X68757Y352724D03*
X71906Y355873D03*
X75056Y359023D03*
X65607Y349574D03*
X71906D03*
X68757D03*
X78206Y359023D03*
X75056Y352724D03*
Y349574D03*
X78206Y355873D03*
X65607D03*
X68757Y362173D03*
Y359023D03*
X71906D03*
X75056Y355873D03*
X71906Y352724D03*
X68757Y355873D03*
X78206Y374733D03*
Y362173D03*
X75056D03*
X71906Y371584D03*
X75056Y365322D03*
X71906D03*
X68757D03*
Y371584D03*
X75056Y374733D03*
X71906D03*
X68757D03*
X65607D03*
X71906Y362173D03*
X78206Y365322D03*
Y371584D03*
X75056Y377883D03*
X68757Y384182D03*
X65607Y387332D03*
X75018Y381033D03*
X68757Y377883D03*
X78206Y381033D03*
X65607D03*
X71906Y377883D03*
X65607Y384182D03*
X68719Y381033D03*
X78206Y377883D03*
X71906Y387332D03*
X71869Y381033D03*
X71906Y384182D03*
X87617Y352724D03*
X90766Y349574D03*
X93916Y352724D03*
X81355Y355873D03*
X90766Y352724D03*
X87617Y349574D03*
X90766Y355873D03*
X87617D03*
X90766Y359023D03*
X81355Y349574D03*
X87617Y359023D03*
Y365322D03*
Y371584D03*
X81355Y365322D03*
Y371584D03*
X90766Y374733D03*
Y362173D03*
X81355D03*
X87617D03*
X81355Y374733D03*
X87617D03*
X90766Y371584D03*
Y365322D03*
X81355Y377883D03*
Y387332D03*
Y384182D03*
X87617D03*
X90766Y377883D03*
X87617Y390481D03*
X81355Y381033D03*
X87617Y387332D03*
X90766Y381033D03*
X87617Y377883D03*
X90766Y390481D03*
Y387332D03*
Y384182D03*
X92360Y394175D03*
X89210D03*
X103365Y346425D03*
X106564Y346400D03*
X100253Y346387D03*
X100215Y352724D03*
X103383Y349556D03*
X93916Y359023D03*
X97066Y355873D03*
X93916Y349574D03*
X97066D03*
X106515Y352724D03*
X106514Y349574D03*
X97066Y352724D03*
X100215Y355873D03*
X93916D03*
X100215Y349574D03*
X103383Y387350D03*
X100215Y384182D03*
X93916Y377883D03*
X97066Y381033D03*
X100215Y387332D03*
X97066D03*
X93916Y384182D03*
X97066D03*
X100215Y381033D03*
X93916D03*
Y387332D03*
X166300Y212300D03*
X175359Y153286D03*
X181495Y153449D03*
X175196Y159748D03*
X178346Y162898D03*
Y156599D03*
X181495Y159748D03*
X175196Y156599D03*
X181495D03*
Y166047D03*
X184645D03*
X181495Y162898D03*
X178346Y159748D03*
Y172347D03*
X181495Y178646D03*
Y175496D03*
X184645Y181795D03*
X181495D03*
Y172347D03*
X184645Y175496D03*
X174569Y180202D03*
X178346Y175496D03*
X175196Y172347D03*
X173000Y170200D03*
X181495Y169197D03*
X178346Y184945D03*
X181495D03*
Y197506D03*
X178346D03*
Y191244D03*
X181495D03*
X175196Y197506D03*
X174336Y192800D03*
X181495Y188095D03*
X178346D03*
X175196Y200655D03*
X178346D03*
Y210104D03*
X181495Y203805D03*
Y206955D03*
X175196Y210104D03*
X178346Y206955D03*
X175196D03*
Y203805D03*
X178346D03*
X171836Y200655D03*
Y198300D03*
X181495Y200655D03*
X178346Y213254D03*
Y225852D03*
X181495Y219553D03*
X175196Y213254D03*
X184645Y219553D03*
X178346Y229002D03*
X181495Y225852D03*
Y222703D03*
X184645Y229002D03*
X174600Y217800D03*
X181495Y216403D03*
X174079Y234604D03*
X175196Y229002D03*
X181495D03*
X187794Y153449D03*
X192400Y152804D03*
X184645Y153449D03*
X197243Y156599D03*
X187794Y159748D03*
X197243Y166047D03*
X194094Y162898D03*
X197243Y159748D03*
X194094D03*
X197243Y162898D03*
X184645Y156599D03*
X187794Y162898D03*
Y166047D03*
X184645Y162898D03*
Y159748D03*
X190944Y162898D03*
Y159748D03*
X194094Y166047D03*
X190944D03*
X200393Y162898D03*
X187794Y156599D03*
Y178646D03*
X197243D03*
X187794Y181795D03*
X194094Y169197D03*
X190944Y172347D03*
Y175496D03*
X197243D03*
X190944Y178646D03*
Y181795D03*
X187794Y175496D03*
X184645Y178646D03*
X190944Y169197D03*
X187794Y172347D03*
X184645Y169197D03*
Y172347D03*
X187794Y169197D03*
X197243Y191244D03*
Y197506D03*
Y184945D03*
X190944Y197506D03*
Y184945D03*
Y188095D03*
Y191244D03*
X187794Y197506D03*
Y184945D03*
X184645Y197506D03*
Y184945D03*
Y191244D03*
Y188095D03*
X197243Y203805D03*
X184645Y206955D03*
X197243Y200655D03*
X190944D03*
Y210104D03*
Y203805D03*
X187794Y200655D03*
X184645Y210104D03*
Y200655D03*
Y203805D03*
X187794Y210104D03*
X190944Y219553D03*
X194094Y222703D03*
X200393Y229002D03*
X194094Y225852D03*
X187794D03*
Y219553D03*
X197243D03*
X187794Y213254D03*
X190944D03*
Y222702D03*
X200393Y222703D03*
X197243Y225852D03*
Y222703D03*
X184645Y225852D03*
X187794Y222703D03*
X184645D03*
Y213254D03*
X194094Y219553D03*
Y232151D03*
X184645D03*
X187794Y229002D03*
X197243Y235301D03*
X194094Y229002D03*
X197243D03*
Y232151D03*
X209842Y153449D03*
Y159748D03*
X206692Y156599D03*
X209842D03*
X203542Y166047D03*
X206692Y162898D03*
X203542D03*
X200393Y159748D03*
X209842Y166047D03*
Y162898D03*
X212991D03*
X203542Y159748D03*
X200393Y166047D03*
X206692D03*
X212991D03*
X206692Y159748D03*
X209842Y169197D03*
X203542D03*
X212991D03*
X206692D03*
X212991Y181795D03*
X206692Y178646D03*
X209842Y181795D03*
X200393Y169197D03*
X206692Y181795D03*
X203542Y175496D03*
X206692D03*
X209842D03*
X200393D03*
X203542Y191244D03*
X206692D03*
X209842Y184945D03*
X200393Y191244D03*
X203542Y197506D03*
X209842D03*
X212991Y184945D03*
Y197506D03*
X203542Y210104D03*
X212991Y206955D03*
Y210104D03*
X209842D03*
X200393D03*
X203542Y200655D03*
X209842D03*
X203542Y206955D03*
X212991Y203805D03*
X206692Y206955D03*
X209842D03*
X200393D03*
X212991Y200655D03*
Y219553D03*
Y213254D03*
X200393D03*
Y219553D03*
X212991Y222740D03*
X209842Y213254D03*
Y225852D03*
X203542Y222703D03*
X200393Y225852D03*
X206692Y219553D03*
X203542Y225852D03*
X206692Y229002D03*
X212991D03*
X203542Y219553D03*
X206692Y222703D03*
X209842D03*
X212991Y225890D03*
X206692Y225852D03*
X203542Y229002D03*
Y232151D03*
X209746Y235397D03*
X203542Y235301D03*
X209842Y232151D03*
X200393D03*
X206692D03*
X212991D03*
X209842Y229002D03*
X225658Y153369D03*
X225552Y156599D03*
Y159748D03*
X222402Y162898D03*
X219253Y166047D03*
X225552Y162898D03*
Y166047D03*
X222402D03*
X219253Y159748D03*
X222402D03*
X219253Y162898D03*
Y156599D03*
X222402D03*
X217697Y174852D03*
X219253Y178646D03*
X225552D03*
X222402Y169197D03*
Y178646D03*
X225552Y181795D03*
X214547Y174852D03*
X225552Y169197D03*
X219253D03*
X219290Y191207D03*
X225552Y184945D03*
Y197543D03*
Y191244D03*
Y188095D03*
X222402Y191244D03*
X219253Y197506D03*
X222402D03*
X219253Y188095D03*
X222402Y206955D03*
X219253Y200655D03*
Y206955D03*
Y210104D03*
Y203805D03*
X222402Y213254D03*
X219253D03*
X228739Y222703D03*
X216141D03*
X228702Y229002D03*
X225590Y222720D03*
X216103Y219591D03*
X219253Y219553D03*
X225590Y225852D03*
X222440Y222703D03*
X225552Y219553D03*
X222402D03*
Y229002D03*
X222440Y225852D03*
X219290D03*
Y222703D03*
X219253Y232151D03*
X225552Y229002D03*
X219253D03*
X235001Y153449D03*
X228702Y162898D03*
X238150D03*
X235001Y166047D03*
X231851D03*
X238150D03*
X228702Y159748D03*
Y166047D03*
X238150Y156599D03*
X235001D03*
X231851D03*
Y162898D03*
Y159748D03*
X235001Y162898D03*
Y159748D03*
X238150D03*
X241300D03*
X228702Y169197D03*
X238150D03*
X231851D03*
Y178646D03*
X235001Y169197D03*
X241300Y175496D03*
Y178646D03*
Y172347D03*
X235001Y178646D03*
Y175496D03*
X228702Y181795D03*
Y178646D03*
X231851Y191244D03*
X241300D03*
X235001Y184945D03*
X228702Y191244D03*
X235001Y188095D03*
Y191244D03*
Y197506D03*
X241300Y184945D03*
Y197506D03*
Y188095D03*
X235001Y200655D03*
Y206955D03*
X244450Y200655D03*
X228702D03*
X235001Y203805D03*
X231851D03*
X228702D03*
X241300Y200655D03*
Y210104D03*
X235001D03*
X231851D03*
X228702D03*
X235001Y219553D03*
X241300Y213254D03*
X238150Y219553D03*
X238188Y225852D03*
X228702Y219553D03*
X228739Y213254D03*
X235038Y225890D03*
X228739Y225852D03*
X238150Y222703D03*
X231889Y219591D03*
Y222740D03*
X235038D03*
X231889Y225890D03*
X228739Y216441D03*
X241338Y225890D03*
X238630Y235654D03*
X231851Y232151D03*
X241300D03*
X231851Y229002D03*
X241300D03*
X239870Y237596D03*
X242870D03*
X235038Y229039D03*
X255492Y152905D03*
X244450Y156599D03*
X250749Y159748D03*
X244450D03*
X250749Y169197D03*
X247637Y162898D03*
X247599Y166047D03*
X253898Y172347D03*
Y178646D03*
X247599Y181795D03*
Y175496D03*
X253898Y169197D03*
X257048Y172347D03*
X250749Y181795D03*
X244450D03*
X250749Y175496D03*
Y178646D03*
X247599Y172347D03*
X244450Y175496D03*
X250749Y172347D03*
X247599Y178646D03*
X253898Y175496D03*
X244450Y178646D03*
Y172347D03*
X250749Y184945D03*
X244450Y169197D03*
X253898Y191244D03*
Y184945D03*
X247599Y197506D03*
Y188095D03*
X244450Y197506D03*
X247599Y191244D03*
X257048Y197506D03*
X253898D03*
X250749D03*
X247599Y184945D03*
X244450Y188095D03*
X257048Y191244D03*
X250749Y188095D03*
X244450Y184945D03*
X250749Y191244D03*
X244450D03*
X247599Y203805D03*
X253898Y206955D03*
Y200655D03*
X250749Y203805D03*
X247599Y206955D03*
Y210104D03*
X250749Y206955D03*
X247599Y200655D03*
X257048Y206955D03*
X250749Y200655D03*
X257048D03*
X250749Y210104D03*
X244450Y203805D03*
X250749Y222703D03*
Y225852D03*
X253898Y219553D03*
Y222703D03*
X257048Y225890D03*
Y219553D03*
X250749D03*
X257048Y213254D03*
X250749D03*
X247599D03*
X253898D03*
X247637Y225852D03*
X250749Y232151D03*
X257048Y235301D03*
X244020Y235518D03*
X244487Y229002D03*
X244450Y232151D03*
X247599D03*
X253898D03*
X257048D03*
X250749Y229002D03*
X253898D03*
X250749Y235301D03*
X253898D03*
X268510Y179088D03*
X262880Y178977D03*
X267722Y176791D03*
X264222D03*
X271209Y177524D03*
X270472Y188488D03*
X264118Y188095D03*
X268391Y207262D03*
X260269Y207358D03*
X266080Y207262D03*
X262580D03*
X269391Y214593D03*
X261269Y214657D03*
X263580Y214593D03*
X267080D03*
X285980Y163487D03*
X285482Y168102D03*
X286105Y172936D03*
Y182385D03*
X273644Y174267D03*
X282975Y172975D03*
X286105Y176085D03*
X285482Y190187D03*
X286105Y197989D03*
X289254Y194839D03*
X286105Y185534D03*
Y194839D03*
Y201139D03*
Y204288D03*
X286106Y210587D03*
X286105Y213721D03*
X289110Y163487D03*
X292260D03*
X295410Y169786D03*
X292404Y176085D03*
X295410Y172936D03*
X289254Y172792D03*
X292260Y169643D03*
X295410Y179235D03*
X292384Y172936D03*
X289254Y176085D03*
Y182385D03*
X292260Y179235D03*
X289111D03*
X297372Y196616D03*
X292361Y197970D03*
X292404Y191690D03*
X289254D03*
X292404Y185534D03*
Y194983D03*
X295410Y194839D03*
X295411Y185534D03*
X289254D03*
Y197989D03*
X289091Y204331D03*
X289254Y210587D03*
X298714Y210477D03*
X292404Y210587D03*
Y201282D03*
X299667Y201334D03*
X292404Y213737D03*
X289254Y201139D03*
X295410Y210587D03*
X289254Y213737D03*
X308008Y163487D03*
X311158D03*
X308008Y166637D03*
X314307Y163487D03*
X314930Y168140D03*
X311301Y182385D03*
X314930Y171289D03*
Y177588D03*
X305002Y176085D03*
Y169786D03*
Y172936D03*
X308152Y169786D03*
X311158Y169643D03*
X308152Y172936D03*
Y176085D03*
Y182385D03*
X305002Y179235D03*
X308152D03*
X314930Y180738D03*
Y174439D03*
X311158Y185534D03*
X314307Y191690D03*
X311158Y194839D03*
X308008Y191690D03*
X311158D03*
X308008Y188540D03*
Y185391D03*
Y198133D03*
X314307Y185534D03*
X311158Y188540D03*
X308008Y194839D03*
X311158Y197989D03*
X314307Y194839D03*
Y197989D03*
X311158Y204288D03*
X314307Y207438D03*
X303940Y212664D03*
X311158Y201139D03*
X308008Y207438D03*
X308152Y204432D03*
X305002D03*
X311158Y210587D03*
X308008Y210731D03*
X305002Y210587D03*
X314307Y201139D03*
Y204288D03*
Y210587D03*
X308460Y214178D03*
X311158Y213737D03*
X314307D03*
G54D83*
X121095Y68911D03*
X128575Y61037D03*
Y68911D03*
X293630Y84000D03*
X297370D03*
X303130D03*
X306870D03*
G54D74*
X69750Y271100D03*
Y276900D03*
X80500Y161400D03*
Y155600D03*
X326000Y314100D03*
Y319900D03*
G54D92*
X138261Y216285D03*
Y224159D03*
Y218253D03*
Y220222D03*
Y222191D03*
X150467Y224159D03*
Y216285D03*
Y222191D03*
Y220222D03*
Y218253D03*
G54D65*
X59303Y421214D03*
Y416096D03*
X51823D03*
Y418655D03*
Y421214D03*
G54D29*
X32914Y184247D03*
X21209Y259777D03*
X46984Y38000D03*
X45070Y58317D03*
X47203Y187525D03*
X45370Y191535D03*
X40233Y184311D03*
X45468Y210701D03*
X44388Y259638D03*
X39884Y317100D03*
X37984Y338000D03*
X40984Y348500D03*
Y352000D03*
X44484Y415700D03*
Y419700D03*
X37584Y411900D03*
Y415700D03*
X53700Y34873D03*
X54884Y220600D03*
X51784Y264600D03*
X49984Y332000D03*
Y336000D03*
Y340000D03*
Y387700D03*
X50384Y397850D03*
Y401350D03*
X92984Y255500D03*
X79484Y259200D03*
X92734Y417000D03*
Y412500D03*
X107484Y80000D03*
X112785Y62963D03*
Y66963D03*
X121784Y350300D03*
X129484Y54300D03*
X126484Y114000D03*
Y131000D03*
X150560Y187354D03*
X158884Y158300D03*
X158584Y163400D03*
X159184Y167100D03*
X158684Y171000D03*
X157284Y195700D03*
X159841Y212568D03*
X155924Y242750D03*
X158284Y301000D03*
Y297000D03*
Y305100D03*
X153584Y432600D03*
X180884Y272800D03*
X178984Y325200D03*
Y329200D03*
X177484Y432600D03*
X185984Y96000D03*
X195284Y111300D03*
X197054Y260830D03*
X186384Y300200D03*
Y304200D03*
X199584Y268700D03*
X205484Y273000D03*
X217404Y97984D03*
X225984Y304600D03*
X226624Y372400D03*
X226614Y383260D03*
X232684Y258200D03*
X249932Y257365D03*
X253297Y268403D03*
X243488Y313514D03*
X250484Y313500D03*
X243488Y319310D03*
X250484Y322000D03*
X261984Y110300D03*
X261384Y259900D03*
X269945Y364610D03*
Y385343D03*
X280234Y123250D03*
X272984Y399500D03*
X300484Y307000D03*
X291484Y372700D03*
X293209Y367508D03*
X292745Y391600D03*
X303484Y57000D03*
X311284Y134300D03*
X308365Y285092D03*
Y281088D03*
Y277100D03*
X307984Y311500D03*
X319084Y62700D03*
X329111Y148439D03*
X337284Y66000D03*
Y74000D03*
X337544Y125500D03*
X336784Y295900D03*
X332984Y358500D03*
Y376500D03*
Y367500D03*
Y372000D03*
Y363000D03*
Y381000D03*
Y385500D03*
G54D38*
X24996Y254083D03*
G54D56*
X34642Y258807D03*
G54D47*
X23819Y339154D03*
Y349154D03*
Y359154D03*
Y369154D03*
Y379154D03*
Y389154D03*
Y399154D03*
X65709Y52244D03*
X75709Y42244D03*
Y52244D03*
X95709Y42244D03*
X85709D03*
X95709Y52244D03*
X85709D03*
G54D93*
X138013Y365197D03*
Y405749D03*
X153013Y365197D03*
X148013D03*
X143013D03*
Y405749D03*
X148013D03*
X153013D03*
X168013Y365197D03*
X163013D03*
X158013D03*
Y405749D03*
X163013D03*
X168013D03*
X173013Y365197D03*
Y405749D03*
G54D66*
X58839Y465590D03*
X61201D03*
X65925D03*
X73012D03*
X68287D03*
X75374D03*
X80098D03*
X87185D03*
X82461D03*
X89547D03*
X94272D03*
X101358D03*
X108445D03*
X96634D03*
X103721D03*
X115532D03*
X110807D03*
X117894D03*
X144311D03*
X151398D03*
X146673D03*
X158484D03*
X165571D03*
X153760D03*
X160846D03*
X167933D03*
X188445D03*
X195532D03*
X190807D03*
X202618D03*
X209705D03*
X197894D03*
X204980D03*
X212067D03*
X216791D03*
X219154D03*
X223878D03*
X226240D03*
X228602D03*
X230965D03*
X233327D03*
X235689D03*
X238051D03*
X240413D03*
X242776D03*
X245138D03*
X247500D03*
X249862D03*
X271890D03*
X274252D03*
G54D57*
X46925Y360000D03*
X50075D03*
G54D75*
X73819Y288821D03*
X71850D03*
X69882D03*
X74803Y318544D03*
X72835D03*
X70866D03*
X68898D03*
X91535Y288821D03*
X89567D03*
X87598D03*
X85630D03*
X83661D03*
X92520Y318544D03*
X90551D03*
X88583D03*
X86614D03*
X84646D03*
X107283Y288821D03*
X105315D03*
X103347D03*
X101378D03*
X99409D03*
X97441D03*
X95472D03*
X93504D03*
X106299Y318544D03*
X104331D03*
X102362D03*
X100394D03*
X98425D03*
X96457D03*
X94488D03*
X123032Y288821D03*
X121063D03*
X119095D03*
X117126D03*
X115158D03*
X113189D03*
X111221D03*
X109252D03*
X122047Y318544D03*
X120079D03*
X118110D03*
X116142D03*
X114173D03*
X112205D03*
X110236D03*
X108268D03*
X136811Y288821D03*
X134843D03*
X132874D03*
X130906D03*
X128937D03*
X126969D03*
X125000D03*
X137795Y318544D03*
X135827D03*
X133858D03*
X131890D03*
X129921D03*
X127953D03*
X125984D03*
X124016D03*
X140748Y288821D03*
X138780D03*
X141732Y318544D03*
X139764D03*
G54D84*
X120300Y85451D03*
X116560D03*
X112820D03*
Y94900D03*
X116560D03*
X120300D03*
X271066Y118077D03*
X263586D03*
Y127525D03*
X267326D03*
X271066D03*
G54D39*
X24996Y256051D03*
G54D48*
X23819Y409154D03*
X65709Y42244D03*
G54D67*
X56476Y466378D03*
X63563D03*
X70650D03*
X77736D03*
X84823D03*
X91909D03*
X98996D03*
X106083D03*
X113169D03*
X120256D03*
X139587D03*
X141949D03*
X149035D03*
X156122D03*
X163209D03*
X170295D03*
X186083D03*
X193169D03*
X200256D03*
X207343D03*
X214429D03*
X221516D03*
X267165D03*
X269528D03*
X276614D03*
X278976D03*
X281339D03*
X283701D03*
X286063D03*
X288425D03*
X290787D03*
X293150D03*
X295512D03*
X297874D03*
G54D94*
X138012Y366574D03*
Y404370D03*
X153012Y366574D03*
X148012D03*
X143012D03*
Y404370D03*
X148012D03*
X153012D03*
X168012Y366574D03*
X163012D03*
X158012D03*
Y404370D03*
X163012D03*
X168012D03*
X173012Y366574D03*
Y404370D03*
G54D76*
X74419Y417300D03*
X83081Y421040D03*
Y413560D03*
G54D85*
X123376Y105000D03*
Y122500D03*
G54D49*
X48038Y45897D03*
X45479D03*
X42920D03*
Y52897D03*
X48038D03*
G54D58*
X63898Y24764D03*
X90472D03*
X117047D03*
X211142D03*
X237717D03*
G36*
G01X117915Y183421D02*
G02X92715I-12600J0D01*
G01Y186566D01*
X97005D01*
Y183421D01*
G03X113625I8310J0D01*
G01Y189721D01*
G03X97005I-8310J0D01*
G01Y186576D01*
X92715D01*
Y189721D01*
G02X117915I12600J0D01*
G01Y183421D01*
G37*
G54D59*
X59441Y141011D03*
Y148589D03*
X62000D03*
X57141Y197411D03*
X62259D03*
X57141Y204989D03*
X59700D03*
X62259D03*
X64559Y141011D03*
Y148589D03*
X160559Y273711D03*
X158000D03*
X155441D03*
X160559Y281289D03*
X155441D03*
G54D68*
X78031Y123474D03*
X74095D03*
X323795Y282404D03*
X319859D03*
G54D86*
X123474Y101063D03*
Y103032D03*
Y106968D03*
Y118563D03*
Y120532D03*
Y108937D03*
Y124468D03*
Y126437D03*
X126526Y106968D03*
Y103032D03*
Y101063D03*
Y120532D03*
Y118563D03*
Y108937D03*
Y126437D03*
Y124468D03*
G54D95*
X153237Y58583D03*
X165048Y52677D03*
X161111Y58583D03*
X168985D03*
X182764Y52677D03*
X172922D03*
X176859Y58583D03*
X184733D03*
G54D78*
X105316Y213343D03*
G54D96*
X146260Y72126D03*
Y129606D03*
G54D69*
X76063Y125049D03*
X74095Y129379D03*
X78031D03*
X321827Y283979D03*
X319859Y288309D03*
X323795D03*
G54D87*
X115359Y242060D03*
X112800D03*
X110241D03*
Y249540D03*
X112800D03*
X115359D03*
G54D79*
X108776Y47760D03*
Y51500D03*
Y55240D03*
X118224Y47760D03*
Y55240D03*
X121882Y61037D03*
X135824Y240260D03*
X126376D03*
X135824Y247740D03*
X126376Y244000D03*
Y247740D03*
G54D88*
X143118Y44803D03*
X194851D03*
G54D97*
X144364Y220222D03*
G54D89*
X136319Y77244D03*
Y81181D03*
Y85118D03*
Y89055D03*
Y92992D03*
Y96929D03*
Y100866D03*
Y104803D03*
Y108740D03*
Y112677D03*
Y116614D03*
Y120551D03*
Y124488D03*
G54D98*
X144685Y297776D03*
G54D99*
X155205Y52677D03*
M02*
